(lib_symbols
	(symbol "scalenode-cm4-baseboard:AP62301_TSOT" (in_bom yes) (on_board yes)
      (property "Reference" "U" (at 35.56 -2.54 0)
        (effects (font (size 1.27 1.27) (thickness 0.15)) (justify left bottom))
      )
      (property "Value" "AP62301_TSOT" (at 35.56 -7.62 0)
        (effects (font (size 1.27 1.27) (thickness 0.15)) (justify left bottom) hide)
      )
      (property "Footprint" "scalenode-cm4-baseboard-footprints:TSOT23-6" (at 35.56 -10.16 0)
        (effects (font (size 1.27 1.27) (thickness 0.15)) (justify left bottom) hide)
      )
      (property "Datasheet" "https://www.diodes.com/assets/Datasheets/AP62300_AP62301_AP62300T.pdf" (at 35.56 -12.7 0)
        (effects (font (size 1.27 1.27) (thickness 0.15)) (justify left bottom) hide)
      )
      (property "MPN" "AP62301WU-7" (at 35.56 -5.08 0)
        (effects (font (size 1.27 1.27) (thickness 0.15)) (justify left bottom))
      )
      (property "Manufacturer" "Diodes Incorporated" (at 35.56 -15.24 0)
        (effects (font (size 1.27 1.27) (thickness 0.15)) (justify left bottom) hide)
      )
      (property "Author" "Antmicro" (at 35.56 -17.78 0)
        (effects (font (size 1.27 1.27) (thickness 0.15)) (justify left bottom) hide)
      )
      (property "License" "Apache-2.0" (at 35.56 -20.32 0)
        (effects (font (size 1.27 1.27) (thickness 0.15)) (justify left bottom) hide)
      )
      (symbol "AP62301_TSOT_1_1"
        (rectangle (start 2.54 2.54) (end 17.78 -12.7)
          (stroke (width 0.254) (type default))
          (fill (type background))
        )
        (pin power_in line (at 0 -10.16 0) (length 2.54)
          (name "GND" (effects (font (size 1.27 1.27))))
          (number "1" (effects (font (size 1.27 1.27))))
        )
        (pin power_out line (at 20.32 0 180) (length 2.54)
          (name "SW" (effects (font (size 1.27 1.27))))
          (number "2" (effects (font (size 1.27 1.27))))
        )
        (pin power_in line (at 0 0 0) (length 2.54)
          (name "VIN" (effects (font (size 1.27 1.27))))
          (number "3" (effects (font (size 1.27 1.27))))
        )
        (pin input line (at 20.32 -10.16 180) (length 2.54)
          (name "FB" (effects (font (size 1.27 1.27))))
          (number "4" (effects (font (size 1.27 1.27))))
        )
        (pin input line (at 0 -5.08 0) (length 2.54)
          (name "EN" (effects (font (size 1.27 1.27))))
          (number "5" (effects (font (size 1.27 1.27))))
        )
        (pin output line (at 20.32 -5.08 180) (length 2.54)
          (name "BST" (effects (font (size 1.27 1.27))))
          (number "6" (effects (font (size 1.27 1.27))))
        )
      )
    )
	(symbol "scalenode-cm4-baseboard:BSS138-7-F" (pin_names (offset 0)) (in_bom yes) (on_board yes)
      (property "Reference" "Q" (at 22.86 -2.54 0)
        (effects (font (size 1.27 1.27) (thickness 0.15)) (justify left bottom))
      )
      (property "Value" "BSS138-7-F" (at 22.86 -5.08 0)
        (effects (font (size 1.27 1.27) (thickness 0.15)) (justify left bottom))
      )
      (property "Footprint" "scalenode-cm4-baseboard-footprints:SOT-23-3" (at 22.86 -7.62 0)
        (effects (font (size 1.27 1.27) (thickness 0.15)) (justify left bottom) hide)
      )
      (property "Datasheet" "https://www.diodes.com/assets/Datasheets/ds30144.pdf" (at 22.86 -10.16 0)
        (effects (font (size 1.27 1.27) (thickness 0.15)) (justify left bottom) hide)
      )
      (property "MPN" "BSS138-7-F" (at 22.86 -12.7 0)
        (effects (font (size 1.27 1.27) (thickness 0.15)) (justify left bottom) hide)
      )
      (property "Manufacturer" "Diodes Incorporated" (at 22.86 -15.24 0)
        (effects (font (size 1.27 1.27) (thickness 0.15)) (justify left bottom) hide)
      )
      (property "Author" "Antmicro" (at 22.86 -17.78 0)
        (effects (font (size 1.27 1.27) (thickness 0.15)) (justify left bottom) hide)
      )
      (property "License" "Apache-2.0" (at 22.86 -20.32 0)
        (effects (font (size 1.27 1.27) (thickness 0.15)) (justify left bottom) hide)
      )
      (symbol "BSS138-7-F_1_1"
        (polyline
          (pts
            (xy 5.08 1.143)
            (xy 5.08 0.635)
          )
          (stroke (width 0.254) (type default))
          (fill (type background))
        )
        (polyline
          (pts
            (xy 5.08 1.143)
            (xy 5.08 1.651)
          )
          (stroke (width 0.254) (type default))
          (fill (type background))
        )
        (polyline
          (pts
            (xy 5.08 2.54)
            (xy 5.08 2.032)
          )
          (stroke (width 0.254) (type default))
          (fill (type background))
        )
        (polyline
          (pts
            (xy 5.08 2.54)
            (xy 5.08 3.048)
          )
          (stroke (width 0.254) (type default))
          (fill (type background))
        )
        (polyline
          (pts
            (xy 5.08 4.445)
            (xy 5.08 3.429)
          )
          (stroke (width 0.254) (type default))
          (fill (type background))
        )
        (polyline
          (pts
            (xy 7.62 1.143)
            (xy 5.08 1.143)
          )
          (stroke (width 0.254) (type default))
          (fill (type background))
        )
        (polyline
          (pts
            (xy 9.144 3.048)
            (xy 8.128 3.048)
          )
          (stroke (width 0.254) (type default))
          (fill (type background))
        )
        (polyline
          (pts
            (xy 2.54 0)
            (xy 4.572 0)
            (xy 4.572 3.937)
          )
          (stroke (width 0.254) (type default))
          (fill (type none))
        )
        (polyline
          (pts
            (xy 7.62 -1.27)
            (xy 7.62 2.54)
            (xy 5.08 2.54)
          )
          (stroke (width 0.254) (type default))
          (fill (type none))
        )
        (polyline
          (pts
            (xy 7.62 6.35)
            (xy 7.62 3.937)
            (xy 5.08 3.937)
          )
          (stroke (width 0.254) (type default))
          (fill (type none))
        )
        (polyline
          (pts
            (xy 5.08 2.54)
            (xy 5.842 3.048)
            (xy 5.842 2.032)
            (xy 5.08 2.54)
          )
          (stroke (width 0.254) (type default))
          (fill (type outline))
        )
        (polyline
          (pts
            (xy 8.636 3.048)
            (xy 8.128 2.286)
            (xy 9.144 2.286)
            (xy 8.636 3.048)
          )
          (stroke (width 0.254) (type default))
          (fill (type outline))
        )
        (polyline
          (pts
            (xy 7.493 0.635)
            (xy 8.636 0.635)
            (xy 8.636 3.937)
            (xy 8.636 4.445)
            (xy 7.493 4.445)
          )
          (stroke (width 0.254) (type default))
          (fill (type background))
        )
        (circle (center 6.35 2.54) (radius 3.302)
          (stroke (width 0.254) (type default))
          (fill (type background))
        )
        (circle (center 7.62 0.635) (radius 0.127)
          (stroke (width 0.254) (type default))
          (fill (type background))
        )
        (circle (center 7.62 1.143) (radius 0.127)
          (stroke (width 0.254) (type default))
          (fill (type background))
        )
        (circle (center 7.62 4.445) (radius 0.127)
          (stroke (width 0.254) (type default))
          (fill (type background))
        )
        (pin bidirectional line (at 0 0 0) (length 2.54)
          (name "G" (effects (font (size 1.27 1.27))))
          (number "1" (effects (font (size 1.27 1.27))))
        )
        (pin bidirectional line (at 7.62 -3.81 90) (length 2.54)
          (name "S" (effects (font (size 1.27 1.27))))
          (number "2" (effects (font (size 1.27 1.27))))
        )
        (pin bidirectional line (at 7.62 8.89 270) (length 2.54)
          (name "D" (effects (font (size 1.27 1.27))))
          (number "3" (effects (font (size 1.27 1.27))))
        )
      )
    )
	(symbol "scalenode-cm4-baseboard:Bus_M.2_MDT580M01001" (in_bom yes) (on_board yes)
      (property "Reference" "U" (at 52.07 -2.54 0)
        (effects (font (size 1.27 1.27) (thickness 0.15)) (justify left bottom))
      )
      (property "Value" "Bus_M.2_MDT580M01001" (at 52.07 -5.08 0)
        (effects (font (size 1.27 1.27) (thickness 0.15)) (justify left bottom))
      )
      (property "Footprint" "scalenode-cm4-baseboard-footprints:Bus_M.2_Socket_Key_M_Amphenol_MDT580M01001" (at 52.07 -7.62 0)
        (effects (font (size 1.27 1.27) (thickness 0.15)) (justify left bottom) hide)
      )
      (property "Datasheet" "https://cdn.amphenol-cs.com/media/wysiwyg/files/documentation/gs-12-1248.pdf" (at 52.07 -10.16 0)
        (effects (font (size 1.27 1.27) (thickness 0.15)) (justify left bottom) hide)
      )
      (property "MPN" "MDT580M01001" (at 52.07 -12.7 0)
        (effects (font (size 1.27 1.27) (thickness 0.15)) (justify left bottom) hide)
      )
      (property "Manufacturer" "Amphenol" (at 52.07 -15.24 0)
        (effects (font (size 1.27 1.27) (thickness 0.15)) (justify left bottom) hide)
      )
      (property "Author" "Antmicro" (at 52.07 -17.78 0)
        (effects (font (size 1.27 1.27) (thickness 0.15)) (justify left bottom) hide)
      )
      (property "License" "Apache-2.0" (at 52.07 -20.32 0)
        (effects (font (size 1.27 1.27) (thickness 0.15)) (justify left bottom) hide)
      )
      (property "ki_description" "PCI connector" (at 0 0 0)
        (effects (font (size 1.27 1.27)) hide)
      )
      (symbol "Bus_M.2_MDT580M01001_0_0"
        (text "KEY-M" (at 19.05 -10.16 0)
          (effects (font (size 1.27 1.27) bold))
        )
      )
      (symbol "Bus_M.2_MDT580M01001_1_1"
        (rectangle (start 3.81 2.54) (end 34.29 -67.31)
          (stroke (width 0.254) (type default))
          (fill (type background))
        )
        (pin passive line (at 0 -64.77 0) (length 3.81)
          (name "GND" (effects (font (size 1.27 1.27))))
          (number "1" (effects (font (size 1.27 1.27))))
        )
        (pin passive line (at 0 -39.37 0) (length 3.81)
          (name "LED" (effects (font (size 1.27 1.27))))
          (number "10" (effects (font (size 1.27 1.27))))
        )
        (pin passive line (at 38.1 -57.15 180) (length 3.81)
          (name "PET3_N" (effects (font (size 1.27 1.27))))
          (number "11" (effects (font (size 1.27 1.27))))
        )
        (pin passive line (at 0 0 0) (length 3.81)
          (name "3V3" (effects (font (size 1.27 1.27))))
          (number "12" (effects (font (size 1.27 1.27))))
        )
        (pin passive line (at 38.1 -54.61 180) (length 3.81)
          (name "PET3_P" (effects (font (size 1.27 1.27))))
          (number "13" (effects (font (size 1.27 1.27))))
        )
        (pin passive line (at 0 0 0) (length 3.81) hide
          (name "3V3" (effects (font (size 1.27 1.27))))
          (number "14" (effects (font (size 1.27 1.27))))
        )
        (pin passive line (at 0 -64.77 0) (length 3.81) hide
          (name "GND" (effects (font (size 1.27 1.27))))
          (number "15" (effects (font (size 1.27 1.27))))
        )
        (pin passive line (at 0 0 0) (length 3.81) hide
          (name "3V3" (effects (font (size 1.27 1.27))))
          (number "16" (effects (font (size 1.27 1.27))))
        )
        (pin passive line (at 38.1 -49.53 180) (length 3.81)
          (name "PER2_N" (effects (font (size 1.27 1.27))))
          (number "17" (effects (font (size 1.27 1.27))))
        )
        (pin passive line (at 0 0 0) (length 3.81) hide
          (name "3V3" (effects (font (size 1.27 1.27))))
          (number "18" (effects (font (size 1.27 1.27))))
        )
        (pin passive line (at 38.1 -46.99 180) (length 3.81)
          (name "PER2_P" (effects (font (size 1.27 1.27))))
          (number "19" (effects (font (size 1.27 1.27))))
        )
        (pin passive line (at 0 0 0) (length 3.81) hide
          (name "3V3" (effects (font (size 1.27 1.27))))
          (number "2" (effects (font (size 1.27 1.27))))
        )
        (pin no_connect line (at 3.81 -59.69 0) (length 3.81) hide
          (name "NC" (effects (font (size 1.27 1.27))))
          (number "20" (effects (font (size 1.27 1.27))))
        )
        (pin passive line (at 0 -64.77 0) (length 3.81) hide
          (name "GND" (effects (font (size 1.27 1.27))))
          (number "21" (effects (font (size 1.27 1.27))))
        )
        (pin no_connect line (at 3.81 -59.69 0) (length 3.81) hide
          (name "NC" (effects (font (size 1.27 1.27))))
          (number "22" (effects (font (size 1.27 1.27))))
        )
        (pin passive line (at 38.1 -41.91 180) (length 3.81)
          (name "PET2_N" (effects (font (size 1.27 1.27))))
          (number "23" (effects (font (size 1.27 1.27))))
        )
        (pin no_connect line (at 3.81 -59.69 0) (length 3.81) hide
          (name "NC" (effects (font (size 1.27 1.27))))
          (number "24" (effects (font (size 1.27 1.27))))
        )
        (pin passive line (at 38.1 -39.37 180) (length 3.81)
          (name "PET2_P" (effects (font (size 1.27 1.27))))
          (number "25" (effects (font (size 1.27 1.27))))
        )
        (pin no_connect line (at 3.81 -59.69 0) (length 3.81) hide
          (name "NC" (effects (font (size 1.27 1.27))))
          (number "26" (effects (font (size 1.27 1.27))))
        )
        (pin passive line (at 0 -64.77 0) (length 3.81) hide
          (name "GND" (effects (font (size 1.27 1.27))))
          (number "27" (effects (font (size 1.27 1.27))))
        )
        (pin no_connect line (at 3.81 -59.69 0) (length 3.81) hide
          (name "NC" (effects (font (size 1.27 1.27))))
          (number "28" (effects (font (size 1.27 1.27))))
        )
        (pin passive line (at 38.1 -34.29 180) (length 3.81)
          (name "PER1_N" (effects (font (size 1.27 1.27))))
          (number "29" (effects (font (size 1.27 1.27))))
        )
        (pin passive line (at 0 -64.77 0) (length 3.81) hide
          (name "GND" (effects (font (size 1.27 1.27))))
          (number "3" (effects (font (size 1.27 1.27))))
        )
        (pin no_connect line (at 3.81 -59.69 0) (length 3.81) hide
          (name "NC" (effects (font (size 1.27 1.27))))
          (number "30" (effects (font (size 1.27 1.27))))
        )
        (pin passive line (at 38.1 -31.75 180) (length 3.81)
          (name "PER1_P" (effects (font (size 1.27 1.27))))
          (number "31" (effects (font (size 1.27 1.27))))
        )
        (pin no_connect line (at 3.81 -59.69 0) (length 3.81) hide
          (name "NC" (effects (font (size 1.27 1.27))))
          (number "32" (effects (font (size 1.27 1.27))))
        )
        (pin passive line (at 0 -64.77 0) (length 3.81) hide
          (name "GND" (effects (font (size 1.27 1.27))))
          (number "33" (effects (font (size 1.27 1.27))))
        )
        (pin no_connect line (at 3.81 -59.69 0) (length 3.81) hide
          (name "NC" (effects (font (size 1.27 1.27))))
          (number "34" (effects (font (size 1.27 1.27))))
        )
        (pin passive line (at 38.1 -26.67 180) (length 3.81)
          (name "PET1_N" (effects (font (size 1.27 1.27))))
          (number "35" (effects (font (size 1.27 1.27))))
        )
        (pin no_connect line (at 3.81 -59.69 0) (length 3.81) hide
          (name "NC" (effects (font (size 1.27 1.27))))
          (number "36" (effects (font (size 1.27 1.27))))
        )
        (pin passive line (at 38.1 -24.13 180) (length 3.81)
          (name "PET1_P" (effects (font (size 1.27 1.27))))
          (number "37" (effects (font (size 1.27 1.27))))
        )
        (pin no_connect line (at 3.81 -59.69 0) (length 3.81) hide
          (name "NC" (effects (font (size 1.27 1.27))))
          (number "38" (effects (font (size 1.27 1.27))))
        )
        (pin passive line (at 0 -64.77 0) (length 3.81) hide
          (name "GND" (effects (font (size 1.27 1.27))))
          (number "39" (effects (font (size 1.27 1.27))))
        )
        (pin passive line (at 0 0 0) (length 3.81) hide
          (name "3V3" (effects (font (size 1.27 1.27))))
          (number "4" (effects (font (size 1.27 1.27))))
        )
        (pin passive line (at 0 -36.83 0) (length 3.81)
          (name "SMB_CLK" (effects (font (size 1.27 1.27))))
          (number "40" (effects (font (size 1.27 1.27))))
        )
        (pin passive line (at 38.1 -19.05 180) (length 3.81)
          (name "PER0_N" (effects (font (size 1.27 1.27))))
          (number "41" (effects (font (size 1.27 1.27))))
        )
        (pin passive line (at 0 -34.29 0) (length 3.81)
          (name "SMB_DATA" (effects (font (size 1.27 1.27))))
          (number "42" (effects (font (size 1.27 1.27))))
        )
        (pin passive line (at 38.1 -16.51 180) (length 3.81)
          (name "PER0_P" (effects (font (size 1.27 1.27))))
          (number "43" (effects (font (size 1.27 1.27))))
        )
        (pin passive line (at 0 -31.75 0) (length 3.81)
          (name "ALERT" (effects (font (size 1.27 1.27))))
          (number "44" (effects (font (size 1.27 1.27))))
        )
        (pin passive line (at 0 -64.77 0) (length 3.81) hide
          (name "GND" (effects (font (size 1.27 1.27))))
          (number "45" (effects (font (size 1.27 1.27))))
        )
        (pin no_connect line (at 3.81 -59.69 0) (length 3.81) hide
          (name "NC" (effects (font (size 1.27 1.27))))
          (number "46" (effects (font (size 1.27 1.27))))
        )
        (pin passive line (at 38.1 -11.43 180) (length 3.81)
          (name "PET0_N" (effects (font (size 1.27 1.27))))
          (number "47" (effects (font (size 1.27 1.27))))
        )
        (pin no_connect line (at 3.81 -59.69 0) (length 3.81) hide
          (name "NC" (effects (font (size 1.27 1.27))))
          (number "48" (effects (font (size 1.27 1.27))))
        )
        (pin passive line (at 38.1 -8.89 180) (length 3.81)
          (name "PET0_P" (effects (font (size 1.27 1.27))))
          (number "49" (effects (font (size 1.27 1.27))))
        )
        (pin passive line (at 38.1 -64.77 180) (length 3.81)
          (name "PER3_N" (effects (font (size 1.27 1.27))))
          (number "5" (effects (font (size 1.27 1.27))))
        )
        (pin passive line (at 0 -29.21 0) (length 3.81)
          (name "PERST#" (effects (font (size 1.27 1.27))))
          (number "50" (effects (font (size 1.27 1.27))))
        )
        (pin passive line (at 0 -64.77 0) (length 3.81) hide
          (name "GND" (effects (font (size 1.27 1.27))))
          (number "51" (effects (font (size 1.27 1.27))))
        )
        (pin passive line (at 0 -26.67 0) (length 3.81)
          (name "CLKREQ#" (effects (font (size 1.27 1.27))))
          (number "52" (effects (font (size 1.27 1.27))))
        )
        (pin passive line (at 38.1 -2.54 180) (length 3.81)
          (name "REFCLK_N" (effects (font (size 1.27 1.27))))
          (number "53" (effects (font (size 1.27 1.27))))
        )
        (pin passive line (at 0 -24.13 0) (length 3.81)
          (name "PEWAKE#" (effects (font (size 1.27 1.27))))
          (number "54" (effects (font (size 1.27 1.27))))
        )
        (pin passive line (at 38.1 0 180) (length 3.81)
          (name "REFCLK_P" (effects (font (size 1.27 1.27))))
          (number "55" (effects (font (size 1.27 1.27))))
        )
        (pin no_connect line (at 3.81 -59.69 0) (length 3.81) hide
          (name "NC" (effects (font (size 1.27 1.27))))
          (number "56" (effects (font (size 1.27 1.27))))
        )
        (pin passive line (at 0 -64.77 0) (length 3.81) hide
          (name "GND" (effects (font (size 1.27 1.27))))
          (number "57" (effects (font (size 1.27 1.27))))
        )
        (pin no_connect line (at 3.81 -59.69 0) (length 3.81) hide
          (name "NC" (effects (font (size 1.27 1.27))))
          (number "58" (effects (font (size 1.27 1.27))))
        )
        (pin no_connect line (at 3.81 -59.69 0) (length 3.81) hide
          (name "NC" (effects (font (size 1.27 1.27))))
          (number "6" (effects (font (size 1.27 1.27))))
        )
        (pin no_connect line (at 3.81 -59.69 0) (length 3.81) hide
          (name "NC" (effects (font (size 1.27 1.27))))
          (number "67" (effects (font (size 1.27 1.27))))
        )
        (pin passive line (at 0 -21.59 0) (length 3.81)
          (name "SUSCLK" (effects (font (size 1.27 1.27))))
          (number "68" (effects (font (size 1.27 1.27))))
        )
        (pin no_connect line (at 3.81 -59.69 0) (length 3.81) hide
          (name "NC" (effects (font (size 1.27 1.27))))
          (number "69" (effects (font (size 1.27 1.27))))
        )
        (pin passive line (at 38.1 -62.23 180) (length 3.81)
          (name "PER3_P" (effects (font (size 1.27 1.27))))
          (number "7" (effects (font (size 1.27 1.27))))
        )
        (pin passive line (at 0 0 0) (length 3.81) hide
          (name "3V3" (effects (font (size 1.27 1.27))))
          (number "70" (effects (font (size 1.27 1.27))))
        )
        (pin passive line (at 0 -64.77 0) (length 3.81) hide
          (name "GND" (effects (font (size 1.27 1.27))))
          (number "71" (effects (font (size 1.27 1.27))))
        )
        (pin passive line (at 0 0 0) (length 3.81) hide
          (name "3V3" (effects (font (size 1.27 1.27))))
          (number "72" (effects (font (size 1.27 1.27))))
        )
        (pin passive line (at 0 -64.77 0) (length 3.81) hide
          (name "GND" (effects (font (size 1.27 1.27))))
          (number "73" (effects (font (size 1.27 1.27))))
        )
        (pin passive line (at 0 0 0) (length 3.81) hide
          (name "3V3" (effects (font (size 1.27 1.27))))
          (number "74" (effects (font (size 1.27 1.27))))
        )
        (pin passive line (at 0 -64.77 0) (length 3.81) hide
          (name "GND" (effects (font (size 1.27 1.27))))
          (number "75" (effects (font (size 1.27 1.27))))
        )
        (pin no_connect line (at 3.81 -59.69 0) (length 3.81) hide
          (name "NC" (effects (font (size 1.27 1.27))))
          (number "8" (effects (font (size 1.27 1.27))))
        )
        (pin passive line (at 0 -64.77 0) (length 3.81) hide
          (name "GND" (effects (font (size 1.27 1.27))))
          (number "9" (effects (font (size 1.27 1.27))))
        )
        (pin passive line (at 0 -62.23 0) (length 3.81)
          (name "SHIELD" (effects (font (size 1.27 1.27))))
          (number "SH1" (effects (font (size 1.27 1.27))))
        )
        (pin passive line (at 0 -62.23 0) (length 3.81) hide
          (name "SHIELD" (effects (font (size 1.27 1.27))))
          (number "SH2" (effects (font (size 1.27 1.27))))
        )
      )
    )
	(symbol "scalenode-cm4-baseboard:CAS-120TA" (pin_names hide) (in_bom yes) (on_board yes)
      (property "Reference" "SW" (at 25.4 -2.54 0)
        (effects (font (size 1.27 1.27) (thickness 0.15)) (justify left bottom))
      )
      (property "Value" "CAS-120TA" (at 25.4 -5.08 0)
        (effects (font (size 1.27 1.27) (thickness 0.15)) (justify left bottom))
      )
      (property "Footprint" "scalenode-cm4-baseboard-footprints:Switch_Slide_CAS-120TA" (at 25.4 -7.62 0)
        (effects (font (size 1.27 1.27) (thickness 0.15)) (justify left bottom) hide)
      )
      (property "Datasheet" "https://www.nidec-components.com/e/catalog/switch/cas.pdf" (at 25.4 -10.16 0)
        (effects (font (size 1.27 1.27) (thickness 0.15)) (justify left bottom) hide)
      )
      (property "MPN" "CAS-120TA" (at 25.4 -12.7 0)
        (effects (font (size 1.27 1.27) (thickness 0.15)) (justify left bottom) hide)
      )
      (property "Manufacturer" "Nidec Components" (at 25.4 -15.24 0)
        (effects (font (size 1.27 1.27) (thickness 0.15)) (justify left bottom) hide)
      )
      (property "Author" "Antmicro" (at 25.4 -17.78 0)
        (effects (font (size 1.27 1.27) (thickness 0.15)) (justify left bottom) hide)
      )
      (property "License" "Apache-2.0" (at 25.4 -20.32 0)
        (effects (font (size 1.27 1.27) (thickness 0.15)) (justify left bottom) hide)
      )
      (symbol "CAS-120TA_1_1"
        (polyline
          (pts
            (xy 3.048 0)
            (xy 8.128 2.286)
          )
          (stroke (width 0.254) (type default))
          (fill (type none))
        )
        (circle (center 2.794 0) (radius 0.3556)
          (stroke (width 0.254) (type default))
          (fill (type none))
        )
        (circle (center 7.366 -2.54) (radius 0.3556)
          (stroke (width 0.254) (type default))
          (fill (type none))
        )
        (circle (center 7.62 2.54) (radius 0.3556)
          (stroke (width 0.254) (type default))
          (fill (type none))
        )
        (pin passive line (at 10.16 2.54 180) (length 2.54)
          (name "1" (effects (font (size 1.27 1.27))))
          (number "1" (effects (font (size 1.27 1.27))))
        )
        (pin passive line (at 0 0 0) (length 2.54)
          (name "2" (effects (font (size 1.27 1.27))))
          (number "2" (effects (font (size 1.27 1.27))))
        )
        (pin passive line (at 10.16 -2.54 180) (length 2.54)
          (name "3" (effects (font (size 1.27 1.27))))
          (number "3" (effects (font (size 1.27 1.27))))
        )
      )
    )
	(symbol "scalenode-cm4-baseboard:C_100n_0402" (pin_numbers hide) (pin_names hide) (in_bom yes) (on_board yes)
      (property "Reference" "C" (at 20.32 -5.08 0)
        (effects (font (size 1.27 1.27) (thickness 0.15)) (justify left bottom))
      )
      (property "Value" "C_100n_0402" (at 20.32 -10.16 0)
        (effects (font (size 1.27 1.27) (thickness 0.15)) (justify left bottom) hide)
      )
      (property "Footprint" "scalenode-cm4-baseboard-footprints:C_0402_1005Metric" (at 20.32 -12.7 0)
        (effects (font (size 1.27 1.27) (thickness 0.15)) (justify left bottom) hide)
      )
      (property "Datasheet" "https://www.murata.com/products/productdetail?partno=GRM155R61H104KE14%23" (at 20.32 -15.24 0)
        (effects (font (size 1.27 1.27) (thickness 0.15)) (justify left bottom) hide)
      )
      (property "MPN" "GRM155R61H104KE14D" (at 20.32 -17.78 0)
        (effects (font (size 1.27 1.27) (thickness 0.15)) (justify left bottom) hide)
      )
      (property "Manufacturer" "Murata" (at 20.32 -20.32 0)
        (effects (font (size 1.27 1.27) (thickness 0.15)) (justify left bottom) hide)
      )
      (property "License" "Apache-2.0" (at 20.32 -22.86 0)
        (effects (font (size 1.27 1.27) (thickness 0.15)) (justify left bottom) hide)
      )
      (property "Author" "Antmicro" (at 20.32 -25.4 0)
        (effects (font (size 1.27 1.27) (thickness 0.15)) (justify left bottom) hide)
      )
      (property "Val" "100n" (at 20.32 -7.62 0)
        (effects (font (size 1.27 1.27) (thickness 0.15)) (justify left bottom))
      )
      (property "Voltage" "50V" (at 20.32 -27.94 0)
        (effects (font (size 1.27 1.27)) (justify left bottom) hide)
      )
      (property "Dielectric" "X5R" (at 20.32 -30.48 0)
        (effects (font (size 1.27 1.27)) (justify left bottom) hide)
      )
      (property "ki_description" "SMD Multilayer Ceramic Capacitor, 0.1 µF, 50 V, 0402 [1005 Metric], ± 10%, X5R, GRM Series" (at 0 0 0)
        (effects (font (size 1.27 1.27)) hide)
      )
      (symbol "C_100n_0402_0_1"
        (polyline
          (pts
            (xy 2.032 -1.524)
            (xy 2.032 1.524)
          )
          (stroke (width 0.3048) (type default))
          (fill (type none))
        )
        (polyline
          (pts
            (xy 3.048 -1.524)
            (xy 3.048 1.524)
          )
          (stroke (width 0.3302) (type default))
          (fill (type none))
        )
      )
      (symbol "C_100n_0402_1_1"
        (pin passive line (at 0 0 0) (length 2.032)
          (name "~" (effects (font (size 1.27 1.27))))
          (number "1" (effects (font (size 1.27 1.27))))
        )
        (pin passive line (at 5.08 0 180) (length 2.032)
          (name "~" (effects (font (size 1.27 1.27))))
          (number "2" (effects (font (size 1.27 1.27))))
        )
      )
    )
	(symbol "scalenode-cm4-baseboard:C_100n_0603" (pin_numbers hide) (pin_names hide) (in_bom yes) (on_board yes)
      (property "Reference" "C" (at 20.32 -5.08 0)
        (effects (font (size 1.27 1.27) (thickness 0.15)) (justify left bottom))
      )
      (property "Value" "C_100n_0603" (at 20.32 -10.16 0)
        (effects (font (size 1.27 1.27) (thickness 0.15)) (justify left bottom) hide)
      )
      (property "Footprint" "scalenode-cm4-baseboard-footprints:C_0603_1608Metric" (at 20.32 -12.7 0)
        (effects (font (size 1.27 1.27) (thickness 0.15)) (justify left bottom) hide)
      )
      (property "Datasheet" "https://spicat.kyocera-avx.com/product/mlcc/chartview/0603YC104KAZ2A/" (at 20.32 -15.24 0)
        (effects (font (size 1.27 1.27) (thickness 0.15)) (justify left bottom) hide)
      )
      (property "MPN" "0603YC104KAZ2A" (at 20.32 -17.78 0)
        (effects (font (size 1.27 1.27) (thickness 0.15)) (justify left bottom) hide)
      )
      (property "Manufacturer" "AVX" (at 20.32 -20.32 0)
        (effects (font (size 1.27 1.27) (thickness 0.15)) (justify left bottom) hide)
      )
      (property "License" "Apache-2.0" (at 20.32 -22.86 0)
        (effects (font (size 1.27 1.27) (thickness 0.15)) (justify left bottom) hide)
      )
      (property "Author" "Antmicro" (at 20.32 -25.4 0)
        (effects (font (size 1.27 1.27) (thickness 0.15)) (justify left bottom) hide)
      )
      (property "Val" "100n" (at 20.32 -7.62 0)
        (effects (font (size 1.27 1.27) (thickness 0.15)) (justify left bottom))
      )
      (property "Voltage" "" (at 20.32 -27.94 0)
        (effects (font (size 1.27 1.27)) (justify left bottom) hide)
      )
      (property "Dielectric" "" (at 20.32 -30.48 0)
        (effects (font (size 1.27 1.27)) (justify left bottom) hide)
      )
      (property "ki_description" "SMD Multilayer Ceramic Capacitor, 0.1 µF, 16 V, 0603 [1608 Metric], ± 10%, X7R, AVX 0603 MLCC" (at 0 0 0)
        (effects (font (size 1.27 1.27)) hide)
      )
      (symbol "C_100n_0603_0_1"
        (polyline
          (pts
            (xy 2.032 -1.524)
            (xy 2.032 1.524)
          )
          (stroke (width 0.3048) (type default))
          (fill (type none))
        )
        (polyline
          (pts
            (xy 3.048 -1.524)
            (xy 3.048 1.524)
          )
          (stroke (width 0.3302) (type default))
          (fill (type none))
        )
      )
      (symbol "C_100n_0603_1_1"
        (pin passive line (at 0 0 0) (length 2.032)
          (name "~" (effects (font (size 1.27 1.27))))
          (number "1" (effects (font (size 1.27 1.27))))
        )
        (pin passive line (at 5.08 0 180) (length 2.032)
          (name "~" (effects (font (size 1.27 1.27))))
          (number "2" (effects (font (size 1.27 1.27))))
        )
      )
    )
	(symbol "scalenode-cm4-baseboard:C_100n_100V_0805" (pin_numbers hide) (pin_names hide) (in_bom yes) (on_board yes)
      (property "Reference" "C" (at 20.32 -5.08 0)
        (effects (font (size 1.27 1.27) (thickness 0.15)) (justify left bottom))
      )
      (property "Value" "C_100n_100V_0805" (at 20.32 -10.16 0)
        (effects (font (size 1.27 1.27) (thickness 0.15)) (justify left bottom) hide)
      )
      (property "Footprint" "scalenode-cm4-baseboard-footprints:C_0805_2012Metric" (at 20.32 -12.7 0)
        (effects (font (size 1.27 1.27) (thickness 0.15)) (justify left bottom) hide)
      )
      (property "Datasheet" "https://product.samsungsem.com/mlcc/CL21B104KCFNNN.do" (at 20.32 -15.24 0)
        (effects (font (size 1.27 1.27) (thickness 0.15)) (justify left bottom) hide)
      )
      (property "MPN" "CL21B104KCFNNNE" (at 20.32 -17.78 0)
        (effects (font (size 1.27 1.27) (thickness 0.15)) (justify left bottom) hide)
      )
      (property "Manufacturer" "Samsung Electro-Mechanics" (at 20.32 -20.32 0)
        (effects (font (size 1.27 1.27) (thickness 0.15)) (justify left bottom) hide)
      )
      (property "License" "Apache-2.0" (at 20.32 -22.86 0)
        (effects (font (size 1.27 1.27) (thickness 0.15)) (justify left bottom) hide)
      )
      (property "Author" "Antmicro" (at 20.32 -25.4 0)
        (effects (font (size 1.27 1.27) (thickness 0.15)) (justify left bottom) hide)
      )
      (property "Val" "100n" (at 20.32 -7.62 0)
        (effects (font (size 1.27 1.27) (thickness 0.15)) (justify left bottom))
      )
      (property "Voltage" "100V" (at 20.32 -27.94 0)
        (effects (font (size 1.27 1.27)) (justify left bottom) hide)
      )
      (property "Dielectric" "X7R" (at 20.32 -30.48 0)
        (effects (font (size 1.27 1.27)) (justify left bottom) hide)
      )
      (property "ki_description" "SMT Multilayer Ceramic Capacitor, 0.1 µF, 100 V, 0805 [2012 Metric], ± 10%, X7R, CL" (at 0 0 0)
        (effects (font (size 1.27 1.27)) hide)
      )
      (symbol "C_100n_100V_0805_0_1"
        (polyline
          (pts
            (xy 2.032 -1.524)
            (xy 2.032 1.524)
          )
          (stroke (width 0.3048) (type default))
          (fill (type none))
        )
        (polyline
          (pts
            (xy 3.048 -1.524)
            (xy 3.048 1.524)
          )
          (stroke (width 0.3302) (type default))
          (fill (type none))
        )
      )
      (symbol "C_100n_100V_0805_1_1"
        (pin passive line (at 0 0 0) (length 2.032)
          (name "~" (effects (font (size 1.27 1.27))))
          (number "1" (effects (font (size 1.27 1.27))))
        )
        (pin passive line (at 5.08 0 180) (length 2.032)
          (name "~" (effects (font (size 1.27 1.27))))
          (number "2" (effects (font (size 1.27 1.27))))
        )
      )
    )
	(symbol "scalenode-cm4-baseboard:C_10n_0402" (pin_numbers hide) (pin_names hide) (in_bom yes) (on_board yes)
      (property "Reference" "C" (at 20.32 -5.08 0)
        (effects (font (size 1.27 1.27) (thickness 0.15)) (justify left bottom))
      )
      (property "Value" "C_10n_0402" (at 20.32 -10.16 0)
        (effects (font (size 1.27 1.27) (thickness 0.15)) (justify left bottom) hide)
      )
      (property "Footprint" "scalenode-cm4-baseboard-footprints:C_0402_1005Metric" (at 20.32 -12.7 0)
        (effects (font (size 1.27 1.27) (thickness 0.15)) (justify left bottom) hide)
      )
      (property "Datasheet" "https://www.murata.com/products/productdetail?partno=GRM155R71H103KA88%23" (at 20.32 -15.24 0)
        (effects (font (size 1.27 1.27) (thickness 0.15)) (justify left bottom) hide)
      )
      (property "MPN" "GRM155R71H103KA88D" (at 20.32 -17.78 0)
        (effects (font (size 1.27 1.27) (thickness 0.15)) (justify left bottom) hide)
      )
      (property "Manufacturer" "Murata" (at 20.32 -20.32 0)
        (effects (font (size 1.27 1.27) (thickness 0.15)) (justify left bottom) hide)
      )
      (property "License" "Apache-2.0" (at 20.32 -22.86 0)
        (effects (font (size 1.27 1.27) (thickness 0.15)) (justify left bottom) hide)
      )
      (property "Author" "Antmicro" (at 20.32 -25.4 0)
        (effects (font (size 1.27 1.27) (thickness 0.15)) (justify left bottom) hide)
      )
      (property "Val" "10n" (at 20.32 -7.62 0)
        (effects (font (size 1.27 1.27) (thickness 0.15)) (justify left bottom))
      )
      (property "Voltage" "50V" (at 20.32 -27.94 0)
        (effects (font (size 1.27 1.27)) (justify left bottom) hide)
      )
      (property "Dielectric" "X7R" (at 20.32 -30.48 0)
        (effects (font (size 1.27 1.27)) (justify left bottom) hide)
      )
      (property "ki_description" "SMD Multilayer Ceramic Capacitor, 10000 pF, 50 V, 0402 [1005 Metric], ± 10%, X7R, GRM Series" (at 0 0 0)
        (effects (font (size 1.27 1.27)) hide)
      )
      (symbol "C_10n_0402_0_1"
        (polyline
          (pts
            (xy 2.032 -1.524)
            (xy 2.032 1.524)
          )
          (stroke (width 0.3048) (type default))
          (fill (type none))
        )
        (polyline
          (pts
            (xy 3.048 -1.524)
            (xy 3.048 1.524)
          )
          (stroke (width 0.3302) (type default))
          (fill (type none))
        )
      )
      (symbol "C_10n_0402_1_1"
        (pin passive line (at 0 0 0) (length 2.032)
          (name "~" (effects (font (size 1.27 1.27))))
          (number "1" (effects (font (size 1.27 1.27))))
        )
        (pin passive line (at 5.08 0 180) (length 2.032)
          (name "~" (effects (font (size 1.27 1.27))))
          (number "2" (effects (font (size 1.27 1.27))))
        )
      )
    )
	(symbol "scalenode-cm4-baseboard:C_10u_0603" (pin_numbers hide) (pin_names hide) (in_bom yes) (on_board yes)
      (property "Reference" "C" (at 20.32 -5.08 0)
        (effects (font (size 1.27 1.27) (thickness 0.15)) (justify left bottom))
      )
      (property "Value" "C_10u_0603" (at 20.32 -10.16 0)
        (effects (font (size 1.27 1.27) (thickness 0.15)) (justify left bottom) hide)
      )
      (property "Footprint" "scalenode-cm4-baseboard-footprints:C_0603_1608Metric" (at 20.32 -12.7 0)
        (effects (font (size 1.27 1.27) (thickness 0.15)) (justify left bottom) hide)
      )
      (property "Datasheet" "https://www.murata.com/products/productdetail?partno=GRM188R61A106KE69%23" (at 20.32 -15.24 0)
        (effects (font (size 1.27 1.27) (thickness 0.15)) (justify left bottom) hide)
      )
      (property "MPN" "GRM188R61A106KE69D" (at 20.32 -17.78 0)
        (effects (font (size 1.27 1.27) (thickness 0.15)) (justify left bottom) hide)
      )
      (property "Manufacturer" "Murata" (at 20.32 -20.32 0)
        (effects (font (size 1.27 1.27) (thickness 0.15)) (justify left bottom) hide)
      )
      (property "License" "Apache-2.0" (at 20.32 -22.86 0)
        (effects (font (size 1.27 1.27) (thickness 0.15)) (justify left bottom) hide)
      )
      (property "Author" "Antmicro" (at 20.32 -25.4 0)
        (effects (font (size 1.27 1.27) (thickness 0.15)) (justify left bottom) hide)
      )
      (property "Val" "10u" (at 20.32 -7.62 0)
        (effects (font (size 1.27 1.27) (thickness 0.15)) (justify left bottom))
      )
      (property "Voltage" "" (at 20.32 -27.94 0)
        (effects (font (size 1.27 1.27)) (justify left bottom) hide)
      )
      (property "Dielectric" "template_dielectric" (at 20.32 -30.48 0)
        (effects (font (size 1.27 1.27)) (justify left bottom) hide)
      )
      (property "ki_description" "SMD Multilayer Ceramic Capacitor, 10 µF, 10 V, 0603 [1608 Metric], ± 10%, X5R, GRM Series" (at 0 0 0)
        (effects (font (size 1.27 1.27)) hide)
      )
      (symbol "C_10u_0603_0_1"
        (polyline
          (pts
            (xy 2.032 -1.524)
            (xy 2.032 1.524)
          )
          (stroke (width 0.3048) (type default))
          (fill (type none))
        )
        (polyline
          (pts
            (xy 3.048 -1.524)
            (xy 3.048 1.524)
          )
          (stroke (width 0.3302) (type default))
          (fill (type none))
        )
      )
      (symbol "C_10u_0603_1_1"
        (pin passive line (at 0 0 0) (length 2.032)
          (name "~" (effects (font (size 1.27 1.27))))
          (number "1" (effects (font (size 1.27 1.27))))
        )
        (pin passive line (at 5.08 0 180) (length 2.032)
          (name "~" (effects (font (size 1.27 1.27))))
          (number "2" (effects (font (size 1.27 1.27))))
        )
      )
    )
	(symbol "scalenode-cm4-baseboard:C_1n_0603" (pin_numbers hide) (pin_names hide) (in_bom yes) (on_board yes)
      (property "Reference" "C" (at 20.32 -5.08 0)
        (effects (font (size 1.27 1.27) (thickness 0.15)) (justify left bottom))
      )
      (property "Value" "C_1n_0603" (at 20.32 -10.16 0)
        (effects (font (size 1.27 1.27) (thickness 0.15)) (justify left bottom) hide)
      )
      (property "Footprint" "scalenode-cm4-baseboard-footprints:C_0603_1608Metric" (at 20.32 -12.7 0)
        (effects (font (size 1.27 1.27) (thickness 0.15)) (justify left bottom) hide)
      )
      (property "Datasheet" "https://spicat.kyocera-avx.com/product/mlcc/chartview/06031C102JAT2A/" (at 20.32 -15.24 0)
        (effects (font (size 1.27 1.27) (thickness 0.15)) (justify left bottom) hide)
      )
      (property "MPN" "06031C102JAT2A" (at 20.32 -17.78 0)
        (effects (font (size 1.27 1.27) (thickness 0.15)) (justify left bottom) hide)
      )
      (property "Manufacturer" "AVX" (at 20.32 -20.32 0)
        (effects (font (size 1.27 1.27) (thickness 0.15)) (justify left bottom) hide)
      )
      (property "License" "Apache-2.0" (at 20.32 -22.86 0)
        (effects (font (size 1.27 1.27) (thickness 0.15)) (justify left bottom) hide)
      )
      (property "Author" "Antmicro" (at 20.32 -25.4 0)
        (effects (font (size 1.27 1.27) (thickness 0.15)) (justify left bottom) hide)
      )
      (property "Val" "1n" (at 20.32 -7.62 0)
        (effects (font (size 1.27 1.27) (thickness 0.15)) (justify left bottom))
      )
      (property "Voltage" "" (at 20.32 -27.94 0)
        (effects (font (size 1.27 1.27)) (justify left bottom) hide)
      )
      (property "Dielectric" "" (at 20.32 -30.48 0)
        (effects (font (size 1.27 1.27)) (justify left bottom) hide)
      )
      (property "ki_description" "SMD Multilayer Ceramic Capacitor, 1000 pF, 100 V, 0603 [1608 Metric], ± 5%, X7R, AVX 0603 MLCC" (at 0 0 0)
        (effects (font (size 1.27 1.27)) hide)
      )
      (symbol "C_1n_0603_0_1"
        (polyline
          (pts
            (xy 2.032 -1.524)
            (xy 2.032 1.524)
          )
          (stroke (width 0.3048) (type default))
          (fill (type none))
        )
        (polyline
          (pts
            (xy 3.048 -1.524)
            (xy 3.048 1.524)
          )
          (stroke (width 0.3302) (type default))
          (fill (type none))
        )
      )
      (symbol "C_1n_0603_1_1"
        (pin passive line (at 0 0 0) (length 2.032)
          (name "~" (effects (font (size 1.27 1.27))))
          (number "1" (effects (font (size 1.27 1.27))))
        )
        (pin passive line (at 5.08 0 180) (length 2.032)
          (name "~" (effects (font (size 1.27 1.27))))
          (number "2" (effects (font (size 1.27 1.27))))
        )
      )
    )
	(symbol "scalenode-cm4-baseboard:C_1n_1210_2kV" (pin_numbers hide) (pin_names hide) (in_bom yes) (on_board yes)
      (property "Reference" "C" (at 20.32 -5.08 0)
        (effects (font (size 1.27 1.27) (thickness 0.15)) (justify left bottom))
      )
      (property "Value" "C_1n_1210_2kV" (at 20.32 -10.16 0)
        (effects (font (size 1.27 1.27) (thickness 0.15)) (justify left bottom) hide)
      )
      (property "Footprint" "scalenode-cm4-baseboard-footprints:C_1210_3225Metric" (at 20.32 -12.7 0)
        (effects (font (size 1.27 1.27) (thickness 0.15)) (justify left bottom) hide)
      )
      (property "Datasheet" "https://www.kemet.com/en/us/capacitors/product/C1210C102KGRACTU.html" (at 20.32 -15.24 0)
        (effects (font (size 1.27 1.27) (thickness 0.15)) (justify left bottom) hide)
      )
      (property "MPN" "C1210C102KGRACTU" (at 20.32 -17.78 0)
        (effects (font (size 1.27 1.27) (thickness 0.15)) (justify left bottom) hide)
      )
      (property "Manufacturer" "KEMET" (at 20.32 -20.32 0)
        (effects (font (size 1.27 1.27) (thickness 0.15)) (justify left bottom) hide)
      )
      (property "License" "Apache-2.0" (at 20.32 -22.86 0)
        (effects (font (size 1.27 1.27) (thickness 0.15)) (justify left bottom) hide)
      )
      (property "Author" "Antmicro" (at 20.32 -25.4 0)
        (effects (font (size 1.27 1.27) (thickness 0.15)) (justify left bottom) hide)
      )
      (property "Val" "1n" (at 20.32 -7.62 0)
        (effects (font (size 1.27 1.27) (thickness 0.15)) (justify left bottom))
      )
      (property "Voltage" "2kV" (at 20.32 -27.94 0)
        (effects (font (size 1.27 1.27)) (justify left bottom) hide)
      )
      (property "Dielectric" "" (at 20.32 -30.48 0)
        (effects (font (size 1.27 1.27)) (justify left bottom) hide)
      )
      (property "ki_description" "SMD Multilayer Ceramic Capacitor, High Voltage, 1000 pF, 2 kV, 1210 [3225 Metric], ± 10%, X7R" (at 0 0 0)
        (effects (font (size 1.27 1.27)) hide)
      )
      (symbol "C_1n_1210_2kV_0_1"
        (polyline
          (pts
            (xy 2.032 -1.524)
            (xy 2.032 1.524)
          )
          (stroke (width 0.3048) (type default))
          (fill (type none))
        )
        (polyline
          (pts
            (xy 3.048 -1.524)
            (xy 3.048 1.524)
          )
          (stroke (width 0.3302) (type default))
          (fill (type none))
        )
      )
      (symbol "C_1n_1210_2kV_1_1"
        (pin passive line (at 0 0 0) (length 2.032)
          (name "~" (effects (font (size 1.27 1.27))))
          (number "1" (effects (font (size 1.27 1.27))))
        )
        (pin passive line (at 5.08 0 180) (length 2.032)
          (name "~" (effects (font (size 1.27 1.27))))
          (number "2" (effects (font (size 1.27 1.27))))
        )
      )
    )
	(symbol "scalenode-cm4-baseboard:C_1u_0402" (pin_numbers hide) (pin_names hide) (in_bom yes) (on_board yes)
      (property "Reference" "C" (at 20.32 -5.08 0)
        (effects (font (size 1.27 1.27) (thickness 0.15)) (justify left bottom))
      )
      (property "Value" "C_1u_0402" (at 20.32 -10.16 0)
        (effects (font (size 1.27 1.27) (thickness 0.15)) (justify left bottom) hide)
      )
      (property "Footprint" "scalenode-cm4-baseboard-footprints:C_0402_1005Metric" (at 20.32 -12.7 0)
        (effects (font (size 1.27 1.27) (thickness 0.15)) (justify left bottom) hide)
      )
      (property "Datasheet" "https://product.tdk.com/en/search/capacitor/ceramic/mlcc/info?part_no=C1005X6S1A105K050BC" (at 20.32 -15.24 0)
        (effects (font (size 1.27 1.27) (thickness 0.15)) (justify left bottom) hide)
      )
      (property "MPN" "C1005X6S1A105K050BC" (at 20.32 -17.78 0)
        (effects (font (size 1.27 1.27) (thickness 0.15)) (justify left bottom) hide)
      )
      (property "Manufacturer" "TDK" (at 20.32 -20.32 0)
        (effects (font (size 1.27 1.27) (thickness 0.15)) (justify left bottom) hide)
      )
      (property "License" "Apache-2.0" (at 20.32 -22.86 0)
        (effects (font (size 1.27 1.27) (thickness 0.15)) (justify left bottom) hide)
      )
      (property "Author" "Antmicro" (at 20.32 -25.4 0)
        (effects (font (size 1.27 1.27) (thickness 0.15)) (justify left bottom) hide)
      )
      (property "Val" "1u" (at 20.32 -7.62 0)
        (effects (font (size 1.27 1.27) (thickness 0.15)) (justify left bottom))
      )
      (property "Voltage" "" (at 20.32 -27.94 0)
        (effects (font (size 1.27 1.27)) (justify left bottom) hide)
      )
      (property "Dielectric" "" (at 20.32 -30.48 0)
        (effects (font (size 1.27 1.27)) (justify left bottom) hide)
      )
      (property "ki_description" "SMD Multilayer Ceramic Capacitor, 1 µF, 10 V, 0402 [1005 Metric], ± 10%, X6S, C" (at 0 0 0)
        (effects (font (size 1.27 1.27)) hide)
      )
      (symbol "C_1u_0402_0_1"
        (polyline
          (pts
            (xy 2.032 -1.524)
            (xy 2.032 1.524)
          )
          (stroke (width 0.3048) (type default))
          (fill (type none))
        )
        (polyline
          (pts
            (xy 3.048 -1.524)
            (xy 3.048 1.524)
          )
          (stroke (width 0.3302) (type default))
          (fill (type none))
        )
      )
      (symbol "C_1u_0402_1_1"
        (pin passive line (at 0 0 0) (length 2.032)
          (name "~" (effects (font (size 1.27 1.27))))
          (number "1" (effects (font (size 1.27 1.27))))
        )
        (pin passive line (at 5.08 0 180) (length 2.032)
          (name "~" (effects (font (size 1.27 1.27))))
          (number "2" (effects (font (size 1.27 1.27))))
        )
      )
    )
	(symbol "scalenode-cm4-baseboard:C_1u_0603" (pin_numbers hide) (pin_names hide) (in_bom yes) (on_board yes)
      (property "Reference" "C" (at 20.32 -5.08 0)
        (effects (font (size 1.27 1.27) (thickness 0.15)) (justify left bottom))
      )
      (property "Value" "C_1u_0603" (at 20.32 -10.16 0)
        (effects (font (size 1.27 1.27) (thickness 0.15)) (justify left bottom) hide)
      )
      (property "Footprint" "scalenode-cm4-baseboard-footprints:C_0603_1608Metric" (at 20.32 -12.7 0)
        (effects (font (size 1.27 1.27) (thickness 0.15)) (justify left bottom) hide)
      )
      (property "Datasheet" "https://www.passivecomponent.com/wp-content/uploads/datasheet/WTC_MLCC_General_Purpose.pdf" (at 20.32 -15.24 0)
        (effects (font (size 1.27 1.27) (thickness 0.15)) (justify left bottom) hide)
      )
      (property "MPN" "0603YD105KAT2A" (at 20.32 -17.78 0)
        (effects (font (size 1.27 1.27) (thickness 0.15)) (justify left bottom) hide)
      )
      (property "Manufacturer" "Walsin" (at 20.32 -20.32 0)
        (effects (font (size 1.27 1.27) (thickness 0.15)) (justify left bottom) hide)
      )
      (property "License" "Apache-2.0" (at 20.32 -22.86 0)
        (effects (font (size 1.27 1.27) (thickness 0.15)) (justify left bottom) hide)
      )
      (property "Author" "Antmicro" (at 20.32 -25.4 0)
        (effects (font (size 1.27 1.27) (thickness 0.15)) (justify left bottom) hide)
      )
      (property "Val" "1u" (at 20.32 -7.62 0)
        (effects (font (size 1.27 1.27) (thickness 0.15)) (justify left bottom))
      )
      (property "Voltage" "" (at 20.32 -27.94 0)
        (effects (font (size 1.27 1.27)) (justify left bottom) hide)
      )
      (property "Dielectric" "" (at 20.32 -30.48 0)
        (effects (font (size 1.27 1.27)) (justify left bottom) hide)
      )
      (property "ki_description" "SMD Multilayer Ceramic Capacitor, 1 µF, 16 V, 0603 [1608 Metric], ± 10%, X5R, AVX 0603 MLCC" (at 0 0 0)
        (effects (font (size 1.27 1.27)) hide)
      )
      (symbol "C_1u_0603_0_1"
        (polyline
          (pts
            (xy 2.032 -1.524)
            (xy 2.032 1.524)
          )
          (stroke (width 0.3048) (type default))
          (fill (type none))
        )
        (polyline
          (pts
            (xy 3.048 -1.524)
            (xy 3.048 1.524)
          )
          (stroke (width 0.3302) (type default))
          (fill (type none))
        )
      )
      (symbol "C_1u_0603_1_1"
        (pin passive line (at 0 0 0) (length 2.032)
          (name "~" (effects (font (size 1.27 1.27))))
          (number "1" (effects (font (size 1.27 1.27))))
        )
        (pin passive line (at 5.08 0 180) (length 2.032)
          (name "~" (effects (font (size 1.27 1.27))))
          (number "2" (effects (font (size 1.27 1.27))))
        )
      )
    )
	(symbol "scalenode-cm4-baseboard:C_22u_0805_10V" (pin_numbers hide) (pin_names hide) (in_bom yes) (on_board yes)
      (property "Reference" "C" (at 20.32 -5.08 0)
        (effects (font (size 1.27 1.27) (thickness 0.15)) (justify left bottom))
      )
      (property "Value" "C_22u_0805_10V" (at 20.32 -10.16 0)
        (effects (font (size 1.27 1.27) (thickness 0.15)) (justify left bottom) hide)
      )
      (property "Footprint" "scalenode-cm4-baseboard-footprints:C_0805_2012Metric" (at 20.32 -12.7 0)
        (effects (font (size 1.27 1.27) (thickness 0.15)) (justify left bottom) hide)
      )
      (property "Datasheet" "https://spicat.kyocera-avx.com/product/mlcc/chartview/0805ZD226MAT2A/" (at 20.32 -15.24 0)
        (effects (font (size 1.27 1.27) (thickness 0.15)) (justify left bottom) hide)
      )
      (property "MPN" "0805ZD226MAT2A" (at 20.32 -17.78 0)
        (effects (font (size 1.27 1.27) (thickness 0.15)) (justify left bottom) hide)
      )
      (property "Manufacturer" "AVX" (at 20.32 -20.32 0)
        (effects (font (size 1.27 1.27) (thickness 0.15)) (justify left bottom) hide)
      )
      (property "License" "Apache-2.0" (at 20.32 -22.86 0)
        (effects (font (size 1.27 1.27) (thickness 0.15)) (justify left bottom) hide)
      )
      (property "Author" "Antmicro" (at 20.32 -25.4 0)
        (effects (font (size 1.27 1.27) (thickness 0.15)) (justify left bottom) hide)
      )
      (property "Val" "22u" (at 20.32 -7.62 0)
        (effects (font (size 1.27 1.27) (thickness 0.15)) (justify left bottom))
      )
      (property "Voltage" "" (at 20.32 -27.94 0)
        (effects (font (size 1.27 1.27)) (justify left bottom) hide)
      )
      (property "Dielectric" "" (at 20.32 -30.48 0)
        (effects (font (size 1.27 1.27)) (justify left bottom) hide)
      )
      (property "ki_description" "SMD Multilayer Ceramic Capacitor, 22 µF, 10 V, 0805 [2012 Metric], ± 20%, X5R" (at 0 0 0)
        (effects (font (size 1.27 1.27)) hide)
      )
      (symbol "C_22u_0805_10V_0_1"
        (polyline
          (pts
            (xy 2.032 -1.524)
            (xy 2.032 1.524)
          )
          (stroke (width 0.3048) (type default))
          (fill (type none))
        )
        (polyline
          (pts
            (xy 3.048 -1.524)
            (xy 3.048 1.524)
          )
          (stroke (width 0.3302) (type default))
          (fill (type none))
        )
      )
      (symbol "C_22u_0805_10V_1_1"
        (pin passive line (at 0 0 0) (length 2.032)
          (name "~" (effects (font (size 1.27 1.27))))
          (number "1" (effects (font (size 1.27 1.27))))
        )
        (pin passive line (at 5.08 0 180) (length 2.032)
          (name "~" (effects (font (size 1.27 1.27))))
          (number "2" (effects (font (size 1.27 1.27))))
        )
      )
    )
	(symbol "scalenode-cm4-baseboard:C_22u_100V_2220" (pin_numbers hide) (pin_names hide) (in_bom yes) (on_board yes)
      (property "Reference" "C" (at 20.32 -5.08 0)
        (effects (font (size 1.27 1.27) (thickness 0.15)) (justify left bottom))
      )
      (property "Value" "C_22u_100V_2220" (at 20.32 -10.16 0)
        (effects (font (size 1.27 1.27) (thickness 0.15)) (justify left bottom) hide)
      )
      (property "Footprint" "scalenode-cm4-baseboard-footprints:C_2220_5650Metric" (at 20.32 -12.7 0)
        (effects (font (size 1.27 1.27) (thickness 0.15)) (justify left bottom) hide)
      )
      (property "Datasheet" "https://product.tdk.com/en/search/capacitor/ceramic/mlcc/info?part_no=C5750X7S2A226M280KB" (at 20.32 -15.24 0)
        (effects (font (size 1.27 1.27) (thickness 0.15)) (justify left bottom) hide)
      )
      (property "MPN" "C5750X7S2A226M280KB" (at 20.32 -17.78 0)
        (effects (font (size 1.27 1.27) (thickness 0.15)) (justify left bottom) hide)
      )
      (property "Manufacturer" "TDK" (at 20.32 -20.32 0)
        (effects (font (size 1.27 1.27) (thickness 0.15)) (justify left bottom) hide)
      )
      (property "License" "Apache-2.0" (at 20.32 -22.86 0)
        (effects (font (size 1.27 1.27) (thickness 0.15)) (justify left bottom) hide)
      )
      (property "Author" "Antmicro" (at 20.32 -25.4 0)
        (effects (font (size 1.27 1.27) (thickness 0.15)) (justify left bottom) hide)
      )
      (property "Val" "22u" (at 20.32 -7.62 0)
        (effects (font (size 1.27 1.27) (thickness 0.15)) (justify left bottom))
      )
      (property "Voltage" "100V" (at 20.32 -27.94 0)
        (effects (font (size 1.27 1.27)) (justify left bottom) hide)
      )
      (property "Dielectric" "X7S" (at 20.32 -30.48 0)
        (effects (font (size 1.27 1.27)) (justify left bottom) hide)
      )
      (property "ki_description" "SMT Multilayer Ceramic Capacitor, 22 µF, 100 V, 2220 [5750 Metric], ± 20%, X7S, C" (at 0 0 0)
        (effects (font (size 1.27 1.27)) hide)
      )
      (symbol "C_22u_100V_2220_0_1"
        (polyline
          (pts
            (xy 2.032 -1.524)
            (xy 2.032 1.524)
          )
          (stroke (width 0.3048) (type default))
          (fill (type none))
        )
        (polyline
          (pts
            (xy 3.048 -1.524)
            (xy 3.048 1.524)
          )
          (stroke (width 0.3302) (type default))
          (fill (type none))
        )
      )
      (symbol "C_22u_100V_2220_1_1"
        (pin passive line (at 0 0 0) (length 2.032)
          (name "~" (effects (font (size 1.27 1.27))))
          (number "1" (effects (font (size 1.27 1.27))))
        )
        (pin passive line (at 5.08 0 180) (length 2.032)
          (name "~" (effects (font (size 1.27 1.27))))
          (number "2" (effects (font (size 1.27 1.27))))
        )
      )
    )
	(symbol "scalenode-cm4-baseboard:C_47u_0603" (pin_numbers hide) (pin_names hide) (in_bom yes) (on_board yes)
      (property "Reference" "C" (at 20.32 -5.08 0)
        (effects (font (size 1.27 1.27) (thickness 0.15)) (justify left bottom))
      )
      (property "Value" "C_47u_0603" (at 20.32 -10.16 0)
        (effects (font (size 1.27 1.27) (thickness 0.15)) (justify left bottom) hide)
      )
      (property "Footprint" "scalenode-cm4-baseboard-footprints:C_0603_1608Metric" (at 20.32 -12.7 0)
        (effects (font (size 1.27 1.27) (thickness 0.15)) (justify left bottom) hide)
      )
      (property "Datasheet" "https://www.murata.com/products/productdetail?partno=GRM188R60J476ME15%23" (at 20.32 -15.24 0)
        (effects (font (size 1.27 1.27) (thickness 0.15)) (justify left bottom) hide)
      )
      (property "MPN" "GRM188R60J476ME15D" (at 20.32 -17.78 0)
        (effects (font (size 1.27 1.27) (thickness 0.15)) (justify left bottom) hide)
      )
      (property "Manufacturer" "Murata" (at 20.32 -20.32 0)
        (effects (font (size 1.27 1.27) (thickness 0.15)) (justify left bottom) hide)
      )
      (property "License" "Apache-2.0" (at 20.32 -22.86 0)
        (effects (font (size 1.27 1.27) (thickness 0.15)) (justify left bottom) hide)
      )
      (property "Author" "Antmicro" (at 20.32 -25.4 0)
        (effects (font (size 1.27 1.27) (thickness 0.15)) (justify left bottom) hide)
      )
      (property "Val" "47u" (at 20.32 -7.62 0)
        (effects (font (size 1.27 1.27) (thickness 0.15)) (justify left bottom))
      )
      (property "Voltage" "" (at 20.32 -27.94 0)
        (effects (font (size 1.27 1.27)) (justify left bottom) hide)
      )
      (property "Dielectric" "" (at 20.32 -30.48 0)
        (effects (font (size 1.27 1.27)) (justify left bottom) hide)
      )
      (property "ki_description" "SMD Multilayer Ceramic Capacitor, 47 µF, 6.3 V, 0603 [1608 Metric], ± 20%, X5R, GRM Series" (at 0 0 0)
        (effects (font (size 1.27 1.27)) hide)
      )
      (symbol "C_47u_0603_0_1"
        (polyline
          (pts
            (xy 2.032 -1.524)
            (xy 2.032 1.524)
          )
          (stroke (width 0.3048) (type default))
          (fill (type none))
        )
        (polyline
          (pts
            (xy 3.048 -1.524)
            (xy 3.048 1.524)
          )
          (stroke (width 0.3302) (type default))
          (fill (type none))
        )
      )
      (symbol "C_47u_0603_1_1"
        (pin passive line (at 0 0 0) (length 2.032)
          (name "~" (effects (font (size 1.27 1.27))))
          (number "1" (effects (font (size 1.27 1.27))))
        )
        (pin passive line (at 5.08 0 180) (length 2.032)
          (name "~" (effects (font (size 1.27 1.27))))
          (number "2" (effects (font (size 1.27 1.27))))
        )
      )
    )
	(symbol "scalenode-cm4-baseboard:Compute-Module-4_H1.5mm" (in_bom yes) (on_board yes)
      (property "Reference" "A" (at 12.7 0 0)
        (effects (font (size 1.27 1.27) (thickness 0.15)) (justify left bottom))
      )
      (property "Value" "Compute-Module-4_H1.5mm" (at 12.7 -2.54 0)
        (effects (font (size 1.27 1.27) (thickness 0.15)) (justify left bottom))
      )
      (property "Footprint" "scalenode-cm4-baseboard-footprints:Compute-Module-4_H1.5mm" (at 12.7 -5.08 0)
        (effects (font (size 1.27 1.27) (thickness 0.15)) (justify left bottom) hide)
      )
      (property "Datasheet" "https://datasheets.raspberrypi.com/cm4/cm4-datasheet.pdf" (at 12.7 -7.62 0)
        (effects (font (size 1.27 1.27) (thickness 0.15)) (justify left bottom) hide)
      )
      (property "Manufacturer" "Raspberry Pi" (at 12.7 -10.16 0)
        (effects (font (size 1.27 1.27) (thickness 0.15)) (justify left bottom) hide)
      )
      (property "MPN" "SC0294" (at 16.51 -17.78 0)
        (effects (font (size 1.27 1.27)) hide)
      )
      (property "Author" "Antmicro" (at 12.7 -12.7 0)
        (effects (font (size 1.27 1.27) (thickness 0.15)) (justify left bottom) hide)
      )
      (property "License" "Apache-2.0" (at 12.7 -15.24 0)
        (effects (font (size 1.27 1.27) (thickness 0.15)) (justify left bottom) hide)
      )
      (property "ki_keywords" "MODULE, B2B" (at 0 0 0)
        (effects (font (size 1.27 1.27)) hide)
      )
      (symbol "Compute-Module-4_H1.5mm_1_1"
        (rectangle (start 10.16 0) (end 0 6.35)
          (stroke (width 0.254) (type default))
          (fill (type background))
        )
      )
    )
	(symbol "scalenode-cm4-baseboard:Earth" (power) (pin_names (offset 0)) (in_bom yes) (on_board yes)
      (property "Reference" "#PWR" (at 0 -6.35 0)
        (effects (font (size 1.27 1.27)) hide)
      )
      (property "Value" "Earth" (at 0 -3.81 0)
        (effects (font (size 1.27 1.27)) hide)
      )
      (property "Footprint" "" (at 0 0 0)
        (effects (font (size 1.27 1.27)) hide)
      )
      (property "Datasheet" "" (at 0 0 0)
        (effects (font (size 1.27 1.27)) hide)
      )
      (symbol "Earth_0_1"
        (polyline
          (pts
            (xy -0.635 -1.905)
            (xy 0.635 -1.905)
          )
          (stroke (width 0) (type default))
          (fill (type none))
        )
        (polyline
          (pts
            (xy -0.127 -2.54)
            (xy 0.127 -2.54)
          )
          (stroke (width 0) (type default))
          (fill (type none))
        )
        (polyline
          (pts
            (xy 0 -1.27)
            (xy 0 0)
          )
          (stroke (width 0) (type default))
          (fill (type none))
        )
        (polyline
          (pts
            (xy 1.27 -1.27)
            (xy -1.27 -1.27)
          )
          (stroke (width 0) (type default))
          (fill (type none))
        )
      )
      (symbol "Earth_1_1"
        (pin power_in line (at 0 0 270) (length 0) hide
          (name "Earth" (effects (font (size 1.27 1.27))))
          (number "1" (effects (font (size 1.27 1.27))))
        )
      )
    )
	(symbol "scalenode-cm4-baseboard:FB_220Z_2A_Murata-BLM21PG_0805" (pin_numbers hide) (pin_names hide) (in_bom yes) (on_board yes)
      (property "Reference" "FB" (at 13.97 0 0)
        (effects (font (size 1.27 1.27) (thickness 0.15)) (justify left bottom))
      )
      (property "Value" "FB_220Z_2A_Murata-BLM21PG_0805" (at 13.97 -2.54 0)
        (effects (font (size 1.27 1.27) (thickness 0.15)) (justify left bottom))
      )
      (property "Footprint" "scalenode-cm4-baseboard-footprints:FB_0805_2012Metric" (at 13.97 -5.08 0)
        (effects (font (size 1.27 1.27) (thickness 0.15)) (justify left bottom) hide)
      )
      (property "Datasheet" "https://www.murata.com/products/productdata/8796738977822/ENFA0005.pdf?1653276712000" (at 13.97 -7.62 0)
        (effects (font (size 1.27 1.27) (thickness 0.15)) (justify left bottom) hide)
      )
      (property "MPN" "BLM21PG221SN1D" (at 13.97 -10.16 0)
        (effects (font (size 1.27 1.27) (thickness 0.15)) (justify left bottom) hide)
      )
      (property "Manufacturer" "Murata" (at 13.97 -12.7 0)
        (effects (font (size 1.27 1.27) (thickness 0.15)) (justify left bottom) hide)
      )
      (property "Author" "Antmicro" (at 13.97 -15.24 0)
        (effects (font (size 1.27 1.27) (thickness 0.15)) (justify left bottom) hide)
      )
      (property "License" "Apache-2.0" (at 13.97 -17.78 0)
        (effects (font (size 1.27 1.27) (thickness 0.15)) (justify left bottom) hide)
      )
      (symbol "FB_220Z_2A_Murata-BLM21PG_0805_0_1"
        (polyline
          (pts
            (xy 1.651 0)
            (xy 1.2446 0)
          )
          (stroke (width 0) (type default))
          (fill (type none))
        )
        (polyline
          (pts
            (xy 3.81 0)
            (xy 3.3274 0)
          )
          (stroke (width 0) (type default))
          (fill (type none))
        )
        (polyline
          (pts
            (xy 2.2606 -1.8288)
            (xy 1.0414 -1.1176)
            (xy 2.7432 1.8288)
            (xy 3.9624 1.1176)
            (xy 2.2606 -1.8288)
          )
          (stroke (width 0) (type default))
          (fill (type none))
        )
      )
      (symbol "FB_220Z_2A_Murata-BLM21PG_0805_1_1"
        (pin passive line (at 0 0 0) (length 1.27)
          (name "~" (effects (font (size 1.27 1.27))))
          (number "1" (effects (font (size 1.27 1.27))))
        )
        (pin passive line (at 5.08 0 180) (length 1.27)
          (name "~" (effects (font (size 1.27 1.27))))
          (number "2" (effects (font (size 1.27 1.27))))
        )
      )
    )
	(symbol "scalenode-cm4-baseboard:FT234XD-R" (in_bom yes) (on_board yes)
      (property "Reference" "U" (at 35.56 -2.54 0)
        (effects (font (size 1.27 1.27) (thickness 0.15)) (justify left bottom))
      )
      (property "Value" "FT234XD-R" (at 35.56 -7.62 0)
        (effects (font (size 1.27 1.27) (thickness 0.15)) (justify left bottom) hide)
      )
      (property "Footprint" "scalenode-cm4-baseboard-footprints:DFN-12-1EP_3x3mm" (at 35.56 -10.16 0)
        (effects (font (size 1.27 1.27) (thickness 0.15)) (justify left bottom) hide)
      )
      (property "Datasheet" "http://www.ftdichip.com/Support/Documents/DataSheets/ICs/DS_FT234XD.pdf" (at 35.56 -12.7 0)
        (effects (font (size 1.27 1.27) (thickness 0.15)) (justify left bottom) hide)
      )
      (property "Manufacturer" "FTDI Chip" (at 35.56 -15.24 0)
        (effects (font (size 1.27 1.27) (thickness 0.15)) (justify left bottom) hide)
      )
      (property "MPN" "FT234XD-R" (at 35.56 -5.08 0)
        (effects (font (size 1.27 1.27) (thickness 0.15)) (justify left bottom))
      )
      (property "Author" "Antmicro" (at 35.56 -17.78 0)
        (effects (font (size 1.27 1.27) (thickness 0.15)) (justify left bottom) hide)
      )
      (property "License" "Apache-2.0" (at 35.56 -20.32 0)
        (effects (font (size 1.27 1.27) (thickness 0.15)) (justify left bottom) hide)
      )
      (property "ki_keywords" "SMT, INTERFACE, IC, CONTROLLER, USB, UART" (at 0 0 0)
        (effects (font (size 1.27 1.27)) hide)
      )
      (property "ki_description" "Interface Bridges, USB to UART, 2.97 V, 5.5 V, DFN, 12 Pins, -40 °C" (at 0 0 0)
        (effects (font (size 1.27 1.27)) hide)
      )
      (symbol "FT234XD-R_1_1"
        (rectangle (start 2.54 2.54) (end 20.32 -21.59)
          (stroke (width 0.254) (type default))
          (fill (type background))
        )
        (pin bidirectional line (at 0 -13.97 0) (length 2.54)
          (name "USBDM" (effects (font (size 1.27 1.27))))
          (number "1" (effects (font (size 1.27 1.27))))
        )
        (pin input line (at 22.86 -7.62 180) (length 2.54)
          (name "RXD" (effects (font (size 1.27 1.27))))
          (number "10" (effects (font (size 1.27 1.27))))
        )
        (pin input line (at 22.86 -13.97 180) (length 2.54)
          (name "~{CTS}" (effects (font (size 1.27 1.27))))
          (number "11" (effects (font (size 1.27 1.27))))
        )
        (pin bidirectional line (at 0 -11.43 0) (length 2.54)
          (name "USBDP" (effects (font (size 1.27 1.27))))
          (number "12" (effects (font (size 1.27 1.27))))
        )
        (pin power_in line (at 0 -19.05 0) (length 2.54)
          (name "GND" (effects (font (size 1.27 1.27))))
          (number "13" (effects (font (size 1.27 1.27))))
        )
        (pin input line (at 0 -6.35 0) (length 2.54)
          (name "~{RESET}" (effects (font (size 1.27 1.27))))
          (number "2" (effects (font (size 1.27 1.27))))
        )
        (pin power_out line (at 22.86 0 180) (length 2.54)
          (name "3.3VOUT" (effects (font (size 1.27 1.27))))
          (number "3" (effects (font (size 1.27 1.27))))
        )
        (pin power_in line (at 0 0 0) (length 2.54)
          (name "VCC" (effects (font (size 1.27 1.27))))
          (number "4" (effects (font (size 1.27 1.27))))
        )
        (pin passive line (at 0 -19.05 0) (length 2.54) hide
          (name "GND" (effects (font (size 1.27 1.27))))
          (number "5" (effects (font (size 1.27 1.27))))
        )
        (pin bidirectional line (at 22.86 -19.05 180) (length 2.54)
          (name "CBUS0" (effects (font (size 1.27 1.27))))
          (number "6" (effects (font (size 1.27 1.27))))
        )
        (pin output line (at 22.86 -5.08 180) (length 2.54)
          (name "TXD" (effects (font (size 1.27 1.27))))
          (number "7" (effects (font (size 1.27 1.27))))
        )
        (pin output line (at 22.86 -11.43 180) (length 2.54)
          (name "~{RTS}" (effects (font (size 1.27 1.27))))
          (number "8" (effects (font (size 1.27 1.27))))
        )
        (pin power_in line (at 0 -2.54 0) (length 2.54)
          (name "VCCIO" (effects (font (size 1.27 1.27))))
          (number "9" (effects (font (size 1.27 1.27))))
        )
      )
    )
	(symbol "scalenode-cm4-baseboard:GND" (power) (pin_numbers hide) (pin_names hide) (in_bom yes) (on_board yes)
      (property "Reference" "#PWR" (at 8.89 -2.54 0)
        (effects (font (size 1.27 1.27) (thickness 0.15)) (justify left bottom) hide)
      )
      (property "Value" "GND" (at 8.89 -5.08 0)
        (effects (font (size 1.27 1.27) (thickness 0.15)) (justify left bottom))
      )
      (property "Footprint" "" (at 8.89 -7.62 0)
        (effects (font (size 1.27 1.27) (thickness 0.15)) (justify left bottom) hide)
      )
      (property "Datasheet" "" (at 8.89 -12.7 0)
        (effects (font (size 1.27 1.27) (thickness 0.15)) (justify left bottom) hide)
      )
      (property "Author" "Antmicro" (at 8.89 -7.62 0)
        (effects (font (size 1.27 1.27) (thickness 0.15)) (justify left bottom) hide)
      )
      (property "License" "Apache-2.0" (at 8.89 -10.16 0)
        (effects (font (size 1.27 1.27) (thickness 0.15)) (justify left bottom) hide)
      )
      (symbol "GND_1_1"
        (polyline
          (pts
            (xy 0 0)
            (xy 0 -1.27)
            (xy 1.27 -1.27)
            (xy 0 -2.54)
            (xy -1.27 -1.27)
            (xy 0 -1.27)
          )
          (stroke (width 0) (type default))
          (fill (type none))
        )
        (pin power_in line (at 0 0 270) (length 0)
          (name "GND" (effects (font (size 1.27 1.27))))
          (number "1" (effects (font (size 1.27 1.27))))
        )
      )
    )
	(symbol "scalenode-cm4-baseboard:GNDD" (power) (pin_numbers hide) (pin_names hide) (in_bom yes) (on_board yes)
      (property "Reference" "#PWR" (at 15.24 -2.54 0)
        (effects (font (size 1.27 1.27) (thickness 0.15)) (justify left bottom) hide)
      )
      (property "Value" "GNDD" (at 15.24 -5.08 0)
        (effects (font (size 1.27 1.27) (thickness 0.15)) (justify left bottom))
      )
      (property "Footprint" "" (at 15.24 -10.16 0)
        (effects (font (size 1.27 1.27) (thickness 0.15)) (justify left bottom) hide)
      )
      (property "Datasheet" "" (at 15.24 -12.7 0)
        (effects (font (size 1.27 1.27) (thickness 0.15)) (justify left bottom) hide)
      )
      (property "Author" "Antmicro" (at 15.24 -7.62 0)
        (effects (font (size 1.27 1.27) (thickness 0.15)) (justify left bottom) hide)
      )
      (property "License" "Apache-2.0" (at 15.24 -10.16 0)
        (effects (font (size 1.27 1.27) (thickness 0.15)) (justify left bottom) hide)
      )
      (symbol "GNDD_1_1"
        (rectangle (start -1.27 -1.524) (end 1.27 -2.032)
          (stroke (width 0) (type default))
          (fill (type outline))
        )
        (polyline
          (pts
            (xy 0 0)
            (xy 0 -1.524)
          )
          (stroke (width 0) (type default))
          (fill (type background))
        )
        (pin power_in line (at 0 0 270) (length 0)
          (name "GNDD" (effects (font (size 1.27 1.27))))
          (number "1" (effects (font (size 1.27 1.27))))
        )
      )
    )
	(symbol "scalenode-cm4-baseboard:GND_10" (power) (pin_names (offset 0)) (in_bom yes) (on_board yes)
      (property "Reference" "#PWR" (at 0 -6.35 0)
        (effects (font (size 1.27 1.27)) hide)
      )
      (property "Value" "GND_10" (at 0 -3.81 0)
        (effects (font (size 1.27 1.27)))
      )
      (property "Footprint" "" (at 0 0 0)
        (effects (font (size 1.27 1.27)) hide)
      )
      (property "Datasheet" "" (at 0 0 0)
        (effects (font (size 1.27 1.27)) hide)
      )
      (property "ki_keywords" "power-flag" (at 0 0 0)
        (effects (font (size 1.27 1.27)) hide)
      )
      (property "ki_description" "Power symbol creates a global label with name \"GND\" , ground" (at 0 0 0)
        (effects (font (size 1.27 1.27)) hide)
      )
      (symbol "GND_10_0_1"
        (polyline
          (pts
            (xy 0 0)
            (xy 0 -1.27)
            (xy 1.27 -1.27)
            (xy 0 -2.54)
            (xy -1.27 -1.27)
            (xy 0 -1.27)
          )
          (stroke (width 0) (type default))
          (fill (type none))
        )
      )
      (symbol "GND_10_1_1"
        (pin power_in line (at 0 0 270) (length 0) hide
          (name "GND" (effects (font (size 1.27 1.27))))
          (number "1" (effects (font (size 1.27 1.27))))
        )
      )
    )
	(symbol "scalenode-cm4-baseboard:GND_11" (power) (pin_names (offset 0)) (in_bom yes) (on_board yes)
      (property "Reference" "#PWR" (at 0 -6.35 0)
        (effects (font (size 1.27 1.27)) hide)
      )
      (property "Value" "GND_11" (at 0 -3.81 0)
        (effects (font (size 1.27 1.27)))
      )
      (property "Footprint" "" (at 0 0 0)
        (effects (font (size 1.27 1.27)) hide)
      )
      (property "Datasheet" "" (at 0 0 0)
        (effects (font (size 1.27 1.27)) hide)
      )
      (property "ki_keywords" "power-flag" (at 0 0 0)
        (effects (font (size 1.27 1.27)) hide)
      )
      (property "ki_description" "Power symbol creates a global label with name \"GND\" , ground" (at 0 0 0)
        (effects (font (size 1.27 1.27)) hide)
      )
      (symbol "GND_11_0_1"
        (polyline
          (pts
            (xy 0 0)
            (xy 0 -1.27)
            (xy 1.27 -1.27)
            (xy 0 -2.54)
            (xy -1.27 -1.27)
            (xy 0 -1.27)
          )
          (stroke (width 0) (type default))
          (fill (type none))
        )
      )
      (symbol "GND_11_1_1"
        (pin power_in line (at 0 0 270) (length 0) hide
          (name "GND" (effects (font (size 1.27 1.27))))
          (number "1" (effects (font (size 1.27 1.27))))
        )
      )
    )
	(symbol "scalenode-cm4-baseboard:GND_12" (power) (pin_names (offset 0)) (in_bom yes) (on_board yes)
      (property "Reference" "#PWR" (at 0 -6.35 0)
        (effects (font (size 1.27 1.27)) hide)
      )
      (property "Value" "GND_12" (at 0 -3.81 0)
        (effects (font (size 1.27 1.27)))
      )
      (property "Footprint" "" (at 0 0 0)
        (effects (font (size 1.27 1.27)) hide)
      )
      (property "Datasheet" "" (at 0 0 0)
        (effects (font (size 1.27 1.27)) hide)
      )
      (property "ki_keywords" "power-flag" (at 0 0 0)
        (effects (font (size 1.27 1.27)) hide)
      )
      (property "ki_description" "Power symbol creates a global label with name \"GND\" , ground" (at 0 0 0)
        (effects (font (size 1.27 1.27)) hide)
      )
      (symbol "GND_12_0_1"
        (polyline
          (pts
            (xy 0 0)
            (xy 0 -1.27)
            (xy 1.27 -1.27)
            (xy 0 -2.54)
            (xy -1.27 -1.27)
            (xy 0 -1.27)
          )
          (stroke (width 0) (type default))
          (fill (type none))
        )
      )
      (symbol "GND_12_1_1"
        (pin power_in line (at 0 0 270) (length 0) hide
          (name "GND" (effects (font (size 1.27 1.27))))
          (number "1" (effects (font (size 1.27 1.27))))
        )
      )
    )
	(symbol "scalenode-cm4-baseboard:GND_13" (power) (pin_names (offset 0)) (in_bom yes) (on_board yes)
      (property "Reference" "#PWR" (at 0 -6.35 0)
        (effects (font (size 1.27 1.27)) hide)
      )
      (property "Value" "GND_13" (at 0 -3.81 0)
        (effects (font (size 1.27 1.27)))
      )
      (property "Footprint" "" (at 0 0 0)
        (effects (font (size 1.27 1.27)) hide)
      )
      (property "Datasheet" "" (at 0 0 0)
        (effects (font (size 1.27 1.27)) hide)
      )
      (property "ki_keywords" "power-flag" (at 0 0 0)
        (effects (font (size 1.27 1.27)) hide)
      )
      (property "ki_description" "Power symbol creates a global label with name \"GND\" , ground" (at 0 0 0)
        (effects (font (size 1.27 1.27)) hide)
      )
      (symbol "GND_13_0_1"
        (polyline
          (pts
            (xy 0 0)
            (xy 0 -1.27)
            (xy 1.27 -1.27)
            (xy 0 -2.54)
            (xy -1.27 -1.27)
            (xy 0 -1.27)
          )
          (stroke (width 0) (type default))
          (fill (type none))
        )
      )
      (symbol "GND_13_1_1"
        (pin power_in line (at 0 0 270) (length 0) hide
          (name "GND" (effects (font (size 1.27 1.27))))
          (number "1" (effects (font (size 1.27 1.27))))
        )
      )
    )
	(symbol "scalenode-cm4-baseboard:H6096NL" (in_bom yes) (on_board yes)
      (property "Reference" "L" (at 36.83 -2.54 0)
        (effects (font (size 1.27 1.27) (thickness 0.15)) (justify left bottom))
      )
      (property "Value" "H6096NL" (at 36.83 -7.62 0)
        (effects (font (size 1.27 1.27) (thickness 0.15)) (justify left bottom) hide)
      )
      (property "Footprint" "scalenode-cm4-baseboard-footprints:SOIC127P1594X685-24N" (at 36.83 -10.16 0)
        (effects (font (size 1.27 1.27) (thickness 0.15)) (justify left bottom) hide)
      )
      (property "Datasheet" "https://www.arrow.com/en/products/h6096nl/pulse-electronics-corporation" (at 36.83 -12.7 0)
        (effects (font (size 1.27 1.27) (thickness 0.15)) (justify left bottom) hide)
      )
      (property "Description" "Common Mode Chokes / Filters 1000Base-T SMD PoE+ 350uH .3Ohms 1-Port" (at 36.83 -15.24 0)
        (effects (font (size 1.27 1.27) (thickness 0.15)) (justify left bottom) hide)
      )
      (property "MPN" "H6096NL" (at 36.83 -5.08 0)
        (effects (font (size 1.27 1.27) (thickness 0.15)) (justify left bottom))
      )
      (property "Manufacturer" "Pulse Electronics" (at 36.83 -17.78 0)
        (effects (font (size 1.27 1.27) (thickness 0.15)) (justify left bottom) hide)
      )
      (property "Author" "Antmicro" (at 36.83 -20.32 0)
        (effects (font (size 1.27 1.27) (thickness 0.15)) (justify left bottom) hide)
      )
      (property "License" "Apache-2.0" (at 36.83 -22.86 0)
        (effects (font (size 1.27 1.27) (thickness 0.15)) (justify left bottom) hide)
      )
      (property "ki_description" "Audio Transformers / Signal Transformers 1000Base-T SMD PoE+ 350uH .3Ohms 1-Port" (at 0 0 0)
        (effects (font (size 1.27 1.27)) hide)
      )
      (symbol "H6096NL_1_1"
        (polyline
          (pts
            (xy 2.54 -27.94)
            (xy 21.59 -27.94)
          )
          (stroke (width 0.254) (type default))
          (fill (type none))
        )
        (polyline
          (pts
            (xy 2.54 -17.78)
            (xy 21.59 -17.78)
          )
          (stroke (width 0.254) (type default))
          (fill (type none))
        )
        (polyline
          (pts
            (xy 2.54 -7.62)
            (xy 21.59 -7.62)
          )
          (stroke (width 0.254) (type default))
          (fill (type none))
        )
        (polyline
          (pts
            (xy 8.255 -35.56)
            (xy 10.795 -35.56)
          )
          (stroke (width 0.254) (type default))
          (fill (type none))
        )
        (polyline
          (pts
            (xy 8.255 -25.4)
            (xy 10.795 -25.4)
          )
          (stroke (width 0.254) (type default))
          (fill (type none))
        )
        (polyline
          (pts
            (xy 8.255 -15.24)
            (xy 10.795 -15.24)
          )
          (stroke (width 0.254) (type default))
          (fill (type none))
        )
        (polyline
          (pts
            (xy 8.255 -5.08)
            (xy 10.795 -5.08)
          )
          (stroke (width 0.254) (type default))
          (fill (type none))
        )
        (polyline
          (pts
            (xy 8.89 -33.02)
            (xy 8.255 -33.02)
          )
          (stroke (width 0.254) (type default))
          (fill (type none))
        )
        (polyline
          (pts
            (xy 8.89 -22.86)
            (xy 8.255 -22.86)
          )
          (stroke (width 0.254) (type default))
          (fill (type none))
        )
        (polyline
          (pts
            (xy 8.89 -12.7)
            (xy 8.255 -12.7)
          )
          (stroke (width 0.254) (type default))
          (fill (type none))
        )
        (polyline
          (pts
            (xy 8.89 -2.54)
            (xy 8.255 -2.54)
          )
          (stroke (width 0.254) (type default))
          (fill (type none))
        )
        (polyline
          (pts
            (xy 10.16 -33.02)
            (xy 10.795 -33.02)
          )
          (stroke (width 0.254) (type default))
          (fill (type none))
        )
        (polyline
          (pts
            (xy 10.16 -22.86)
            (xy 10.795 -22.86)
          )
          (stroke (width 0.254) (type default))
          (fill (type none))
        )
        (polyline
          (pts
            (xy 10.16 -12.7)
            (xy 10.795 -12.7)
          )
          (stroke (width 0.254) (type default))
          (fill (type none))
        )
        (polyline
          (pts
            (xy 10.16 -2.54)
            (xy 10.795 -2.54)
          )
          (stroke (width 0.254) (type default))
          (fill (type none))
        )
        (polyline
          (pts
            (xy 11.43 -35.56)
            (xy 11.43 -30.48)
          )
          (stroke (width 0.254) (type default))
          (fill (type none))
        )
        (polyline
          (pts
            (xy 11.43 -25.4)
            (xy 11.43 -20.32)
          )
          (stroke (width 0.254) (type default))
          (fill (type none))
        )
        (polyline
          (pts
            (xy 11.43 -15.24)
            (xy 11.43 -10.16)
          )
          (stroke (width 0.254) (type default))
          (fill (type none))
        )
        (polyline
          (pts
            (xy 11.43 -5.08)
            (xy 11.43 0)
          )
          (stroke (width 0.254) (type default))
          (fill (type none))
        )
        (polyline
          (pts
            (xy 12.065 -35.56)
            (xy 12.065 -30.48)
          )
          (stroke (width 0.254) (type default))
          (fill (type none))
        )
        (polyline
          (pts
            (xy 12.065 -25.4)
            (xy 12.065 -20.32)
          )
          (stroke (width 0.254) (type default))
          (fill (type none))
        )
        (polyline
          (pts
            (xy 12.065 -15.24)
            (xy 12.065 -10.16)
          )
          (stroke (width 0.254) (type default))
          (fill (type none))
        )
        (polyline
          (pts
            (xy 12.065 -5.08)
            (xy 12.065 0)
          )
          (stroke (width 0.254) (type default))
          (fill (type none))
        )
        (polyline
          (pts
            (xy 13.335 -33.02)
            (xy 12.7 -33.02)
          )
          (stroke (width 0.254) (type default))
          (fill (type none))
        )
        (polyline
          (pts
            (xy 13.335 -22.86)
            (xy 12.7 -22.86)
          )
          (stroke (width 0.254) (type default))
          (fill (type none))
        )
        (polyline
          (pts
            (xy 13.335 -12.7)
            (xy 12.7 -12.7)
          )
          (stroke (width 0.254) (type default))
          (fill (type none))
        )
        (polyline
          (pts
            (xy 13.335 -2.54)
            (xy 12.7 -2.54)
          )
          (stroke (width 0.254) (type default))
          (fill (type none))
        )
        (polyline
          (pts
            (xy 14.605 -33.02)
            (xy 15.24 -33.02)
          )
          (stroke (width 0.254) (type default))
          (fill (type none))
        )
        (polyline
          (pts
            (xy 14.605 -22.86)
            (xy 15.24 -22.86)
          )
          (stroke (width 0.254) (type default))
          (fill (type none))
        )
        (polyline
          (pts
            (xy 14.605 -12.7)
            (xy 15.24 -12.7)
          )
          (stroke (width 0.254) (type default))
          (fill (type none))
        )
        (polyline
          (pts
            (xy 14.605 -2.54)
            (xy 15.24 -2.54)
          )
          (stroke (width 0.254) (type default))
          (fill (type none))
        )
        (polyline
          (pts
            (xy 15.24 -35.56)
            (xy 12.7 -35.56)
          )
          (stroke (width 0.254) (type default))
          (fill (type none))
        )
        (polyline
          (pts
            (xy 15.24 -25.4)
            (xy 12.7 -25.4)
          )
          (stroke (width 0.254) (type default))
          (fill (type none))
        )
        (polyline
          (pts
            (xy 15.24 -15.24)
            (xy 12.7 -15.24)
          )
          (stroke (width 0.254) (type default))
          (fill (type none))
        )
        (polyline
          (pts
            (xy 15.24 -5.08)
            (xy 12.7 -5.08)
          )
          (stroke (width 0.254) (type default))
          (fill (type none))
        )
        (polyline
          (pts
            (xy 8.255 -30.48)
            (xy 8.89 -30.48)
            (xy 10.16 -33.02)
            (xy 10.16 -33.02)
          )
          (stroke (width 0.254) (type default))
          (fill (type none))
        )
        (polyline
          (pts
            (xy 8.255 -20.32)
            (xy 8.89 -20.32)
            (xy 10.16 -22.86)
            (xy 10.16 -22.86)
          )
          (stroke (width 0.254) (type default))
          (fill (type none))
        )
        (polyline
          (pts
            (xy 8.255 -10.16)
            (xy 8.89 -10.16)
            (xy 10.16 -12.7)
            (xy 10.16 -12.7)
          )
          (stroke (width 0.254) (type default))
          (fill (type none))
        )
        (polyline
          (pts
            (xy 8.255 0)
            (xy 8.89 0)
            (xy 10.16 -2.54)
            (xy 10.16 -2.54)
          )
          (stroke (width 0.254) (type default))
          (fill (type none))
        )
        (polyline
          (pts
            (xy 8.89 -33.02)
            (xy 10.16 -30.48)
            (xy 10.16 -30.48)
            (xy 10.795 -30.48)
          )
          (stroke (width 0.254) (type default))
          (fill (type none))
        )
        (polyline
          (pts
            (xy 8.89 -22.86)
            (xy 10.16 -20.32)
            (xy 10.16 -20.32)
            (xy 10.795 -20.32)
          )
          (stroke (width 0.254) (type default))
          (fill (type none))
        )
        (polyline
          (pts
            (xy 8.89 -12.7)
            (xy 10.16 -10.16)
            (xy 10.16 -10.16)
            (xy 10.795 -10.16)
          )
          (stroke (width 0.254) (type default))
          (fill (type none))
        )
        (polyline
          (pts
            (xy 8.89 -2.54)
            (xy 10.16 0)
            (xy 10.16 0)
            (xy 10.795 0)
          )
          (stroke (width 0.254) (type default))
          (fill (type none))
        )
        (polyline
          (pts
            (xy 14.605 -33.02)
            (xy 13.97 -31.75)
            (xy 13.335 -30.48)
            (xy 12.7 -30.48)
          )
          (stroke (width 0.254) (type default))
          (fill (type none))
        )
        (polyline
          (pts
            (xy 14.605 -22.86)
            (xy 13.97 -21.59)
            (xy 13.335 -20.32)
            (xy 12.7 -20.32)
          )
          (stroke (width 0.254) (type default))
          (fill (type none))
        )
        (polyline
          (pts
            (xy 14.605 -12.7)
            (xy 13.97 -11.43)
            (xy 13.335 -10.16)
            (xy 12.7 -10.16)
          )
          (stroke (width 0.254) (type default))
          (fill (type none))
        )
        (polyline
          (pts
            (xy 14.605 -2.54)
            (xy 13.97 -1.27)
            (xy 13.335 0)
            (xy 12.7 0)
          )
          (stroke (width 0.254) (type default))
          (fill (type none))
        )
        (polyline
          (pts
            (xy 15.24 -30.48)
            (xy 14.605 -30.48)
            (xy 13.97 -31.75)
            (xy 13.335 -33.02)
          )
          (stroke (width 0.254) (type default))
          (fill (type none))
        )
        (polyline
          (pts
            (xy 15.24 -20.32)
            (xy 14.605 -20.32)
            (xy 13.97 -21.59)
            (xy 13.335 -22.86)
          )
          (stroke (width 0.254) (type default))
          (fill (type none))
        )
        (polyline
          (pts
            (xy 15.24 -10.16)
            (xy 14.605 -10.16)
            (xy 13.97 -11.43)
            (xy 13.335 -12.7)
          )
          (stroke (width 0.254) (type default))
          (fill (type none))
        )
        (polyline
          (pts
            (xy 15.24 0)
            (xy 14.605 0)
            (xy 13.97 -1.27)
            (xy 13.335 -2.54)
          )
          (stroke (width 0.254) (type default))
          (fill (type none))
        )
        (rectangle (start 2.54 2.54) (end 21.59 -38.1)
          (stroke (width 0.254) (type default))
          (fill (type background))
        )
        (circle (center 10.668 -30.734) (radius 0.0001)
          (stroke (width 0.254) (type default))
          (fill (type none))
        )
        (circle (center 10.668 -20.574) (radius 0.0001)
          (stroke (width 0.254) (type default))
          (fill (type none))
        )
        (circle (center 10.668 -10.414) (radius 0.0001)
          (stroke (width 0.254) (type default))
          (fill (type none))
        )
        (circle (center 10.668 -0.254) (radius 0.0001)
          (stroke (width 0.254) (type default))
          (fill (type none))
        )
        (arc (start 10.795 -35.56) (mid 11.058 -34.925) (end 10.795 -34.29)
          (stroke (width 0.254) (type default))
          (fill (type none))
        )
        (arc (start 10.795 -34.29) (mid 11.058 -33.655) (end 10.795 -33.02)
          (stroke (width 0.254) (type default))
          (fill (type none))
        )
        (arc (start 10.795 -33.02) (mid 11.058 -32.385) (end 10.795 -31.75)
          (stroke (width 0.254) (type default))
          (fill (type none))
        )
        (arc (start 10.795 -31.75) (mid 11.058 -31.115) (end 10.795 -30.48)
          (stroke (width 0.254) (type default))
          (fill (type none))
        )
        (arc (start 10.795 -25.4) (mid 11.058 -24.765) (end 10.795 -24.13)
          (stroke (width 0.254) (type default))
          (fill (type none))
        )
        (arc (start 10.795 -24.13) (mid 11.058 -23.495) (end 10.795 -22.86)
          (stroke (width 0.254) (type default))
          (fill (type none))
        )
        (arc (start 10.795 -22.86) (mid 11.058 -22.225) (end 10.795 -21.59)
          (stroke (width 0.254) (type default))
          (fill (type none))
        )
        (arc (start 10.795 -21.59) (mid 11.058 -20.955) (end 10.795 -20.32)
          (stroke (width 0.254) (type default))
          (fill (type none))
        )
        (arc (start 10.795 -15.24) (mid 11.058 -14.605) (end 10.795 -13.97)
          (stroke (width 0.254) (type default))
          (fill (type none))
        )
        (arc (start 10.795 -13.97) (mid 11.058 -13.335) (end 10.795 -12.7)
          (stroke (width 0.254) (type default))
          (fill (type none))
        )
        (arc (start 10.795 -12.7) (mid 11.058 -12.065) (end 10.795 -11.43)
          (stroke (width 0.254) (type default))
          (fill (type none))
        )
        (arc (start 10.795 -11.43) (mid 11.058 -10.795) (end 10.795 -10.16)
          (stroke (width 0.254) (type default))
          (fill (type none))
        )
        (arc (start 10.795 -5.08) (mid 11.058 -4.445) (end 10.795 -3.81)
          (stroke (width 0.254) (type default))
          (fill (type none))
        )
        (arc (start 10.795 -3.81) (mid 11.058 -3.175) (end 10.795 -2.54)
          (stroke (width 0.254) (type default))
          (fill (type none))
        )
        (arc (start 10.795 -2.54) (mid 11.058 -1.905) (end 10.795 -1.27)
          (stroke (width 0.254) (type default))
          (fill (type none))
        )
        (arc (start 10.795 -1.27) (mid 11.058 -0.635) (end 10.795 0)
          (stroke (width 0.254) (type default))
          (fill (type none))
        )
        (arc (start 12.7 -34.29) (mid 12.437 -34.925) (end 12.7 -35.56)
          (stroke (width 0.254) (type default))
          (fill (type none))
        )
        (arc (start 12.7 -33.02) (mid 12.437 -33.655) (end 12.7 -34.29)
          (stroke (width 0.254) (type default))
          (fill (type none))
        )
        (arc (start 12.7 -31.75) (mid 12.437 -32.385) (end 12.7 -33.02)
          (stroke (width 0.254) (type default))
          (fill (type none))
        )
        (arc (start 12.7 -30.48) (mid 12.437 -31.115) (end 12.7 -31.75)
          (stroke (width 0.254) (type default))
          (fill (type none))
        )
        (arc (start 12.7 -24.13) (mid 12.437 -24.765) (end 12.7 -25.4)
          (stroke (width 0.254) (type default))
          (fill (type none))
        )
        (arc (start 12.7 -22.86) (mid 12.437 -23.495) (end 12.7 -24.13)
          (stroke (width 0.254) (type default))
          (fill (type none))
        )
        (arc (start 12.7 -21.59) (mid 12.437 -22.225) (end 12.7 -22.86)
          (stroke (width 0.254) (type default))
          (fill (type none))
        )
        (arc (start 12.7 -20.32) (mid 12.437 -20.955) (end 12.7 -21.59)
          (stroke (width 0.254) (type default))
          (fill (type none))
        )
        (arc (start 12.7 -13.97) (mid 12.437 -14.605) (end 12.7 -15.24)
          (stroke (width 0.254) (type default))
          (fill (type none))
        )
        (arc (start 12.7 -12.7) (mid 12.437 -13.335) (end 12.7 -13.97)
          (stroke (width 0.254) (type default))
          (fill (type none))
        )
        (arc (start 12.7 -11.43) (mid 12.437 -12.065) (end 12.7 -12.7)
          (stroke (width 0.254) (type default))
          (fill (type none))
        )
        (arc (start 12.7 -10.16) (mid 12.437 -10.795) (end 12.7 -11.43)
          (stroke (width 0.254) (type default))
          (fill (type none))
        )
        (arc (start 12.7 -3.81) (mid 12.437 -4.445) (end 12.7 -5.08)
          (stroke (width 0.254) (type default))
          (fill (type none))
        )
        (arc (start 12.7 -2.54) (mid 12.437 -3.175) (end 12.7 -3.81)
          (stroke (width 0.254) (type default))
          (fill (type none))
        )
        (arc (start 12.7 -1.27) (mid 12.437 -1.905) (end 12.7 -2.54)
          (stroke (width 0.254) (type default))
          (fill (type none))
        )
        (arc (start 12.7 0) (mid 12.437 -0.635) (end 12.7 -1.27)
          (stroke (width 0.254) (type default))
          (fill (type none))
        )
        (circle (center 12.827 -30.734) (radius 0.0001)
          (stroke (width 0.254) (type default))
          (fill (type none))
        )
        (circle (center 12.827 -20.574) (radius 0.0001)
          (stroke (width 0.254) (type default))
          (fill (type none))
        )
        (circle (center 12.827 -10.414) (radius 0.0001)
          (stroke (width 0.254) (type default))
          (fill (type none))
        )
        (circle (center 12.827 -0.254) (radius 0.0001)
          (stroke (width 0.254) (type default))
          (fill (type none))
        )
        (pin passive line (at 0 0 0) (length 2.54)
          (name "TCT1" (effects (font (size 1.27 1.27))))
          (number "1" (effects (font (size 1.27 1.27))))
        )
        (pin passive line (at 0 -30.48 0) (length 2.54)
          (name "TCT4" (effects (font (size 1.27 1.27))))
          (number "10" (effects (font (size 1.27 1.27))))
        )
        (pin passive line (at 0 -33.02 0) (length 2.54)
          (name "TD4+" (effects (font (size 1.27 1.27))))
          (number "11" (effects (font (size 1.27 1.27))))
        )
        (pin passive line (at 0 -35.56 0) (length 2.54)
          (name "TD4-" (effects (font (size 1.27 1.27))))
          (number "12" (effects (font (size 1.27 1.27))))
        )
        (pin passive line (at 24.13 -35.56 180) (length 2.54)
          (name "MX4-" (effects (font (size 1.27 1.27))))
          (number "13" (effects (font (size 1.27 1.27))))
        )
        (pin passive line (at 24.13 -33.02 180) (length 2.54)
          (name "MX4+" (effects (font (size 1.27 1.27))))
          (number "14" (effects (font (size 1.27 1.27))))
        )
        (pin passive line (at 24.13 -30.48 180) (length 2.54)
          (name "MCT4" (effects (font (size 1.27 1.27))))
          (number "15" (effects (font (size 1.27 1.27))))
        )
        (pin passive line (at 24.13 -25.4 180) (length 2.54)
          (name "MX3-" (effects (font (size 1.27 1.27))))
          (number "16" (effects (font (size 1.27 1.27))))
        )
        (pin passive line (at 24.13 -22.86 180) (length 2.54)
          (name "MX3+" (effects (font (size 1.27 1.27))))
          (number "17" (effects (font (size 1.27 1.27))))
        )
        (pin passive line (at 24.13 -20.32 180) (length 2.54)
          (name "MCT3" (effects (font (size 1.27 1.27))))
          (number "18" (effects (font (size 1.27 1.27))))
        )
        (pin passive line (at 24.13 -15.24 180) (length 2.54)
          (name "MX2-" (effects (font (size 1.27 1.27))))
          (number "19" (effects (font (size 1.27 1.27))))
        )
        (pin passive line (at 0 -2.54 0) (length 2.54)
          (name "TD1+" (effects (font (size 1.27 1.27))))
          (number "2" (effects (font (size 1.27 1.27))))
        )
        (pin passive line (at 24.13 -12.7 180) (length 2.54)
          (name "MX2+" (effects (font (size 1.27 1.27))))
          (number "20" (effects (font (size 1.27 1.27))))
        )
        (pin passive line (at 24.13 -10.16 180) (length 2.54)
          (name "MCT2" (effects (font (size 1.27 1.27))))
          (number "21" (effects (font (size 1.27 1.27))))
        )
        (pin passive line (at 24.13 -5.08 180) (length 2.54)
          (name "MX1-" (effects (font (size 1.27 1.27))))
          (number "22" (effects (font (size 1.27 1.27))))
        )
        (pin passive line (at 24.13 -2.54 180) (length 2.54)
          (name "MX1+" (effects (font (size 1.27 1.27))))
          (number "23" (effects (font (size 1.27 1.27))))
        )
        (pin passive line (at 24.13 0 180) (length 2.54)
          (name "MCT1" (effects (font (size 1.27 1.27))))
          (number "24" (effects (font (size 1.27 1.27))))
        )
        (pin passive line (at 0 -5.08 0) (length 2.54)
          (name "TD1-" (effects (font (size 1.27 1.27))))
          (number "3" (effects (font (size 1.27 1.27))))
        )
        (pin passive line (at 0 -10.16 0) (length 2.54)
          (name "TCT2" (effects (font (size 1.27 1.27))))
          (number "4" (effects (font (size 1.27 1.27))))
        )
        (pin passive line (at 0 -12.7 0) (length 2.54)
          (name "TD2+" (effects (font (size 1.27 1.27))))
          (number "5" (effects (font (size 1.27 1.27))))
        )
        (pin passive line (at 0 -15.24 0) (length 2.54)
          (name "TD2-" (effects (font (size 1.27 1.27))))
          (number "6" (effects (font (size 1.27 1.27))))
        )
        (pin passive line (at 0 -20.32 0) (length 2.54)
          (name "TCT3" (effects (font (size 1.27 1.27))))
          (number "7" (effects (font (size 1.27 1.27))))
        )
        (pin passive line (at 0 -22.86 0) (length 2.54)
          (name "TD3+" (effects (font (size 1.27 1.27))))
          (number "8" (effects (font (size 1.27 1.27))))
        )
        (pin passive line (at 0 -25.4 0) (length 2.54)
          (name "TD3-" (effects (font (size 1.27 1.27))))
          (number "9" (effects (font (size 1.27 1.27))))
        )
      )
    )
	(symbol "scalenode-cm4-baseboard:Hermaphroditic_Samtec_LSHM_2x30_LSHM-130-01-L-RH-A-S-K-TR" (in_bom yes) (on_board yes)
      (property "Reference" "J" (at 35.56 -2.54 0)
        (effects (font (size 1.27 1.27) (thickness 0.15)) (justify left bottom))
      )
      (property "Value" "Hermaphroditic_Samtec_LSHM_2x30_LSHM-130-01-L-RH-A-S-K-TR" (at 35.56 -5.08 0)
        (effects (font (size 1.27 1.27) (thickness 0.15)) (justify left bottom))
      )
      (property "Footprint" "scalenode-cm4-baseboard-footprints:Conn_Hermaphroditic_Samtec_LSHM_2x30_LSHM-130-01-XXX-RH-A-S-K-XX" (at 35.56 -7.62 0)
        (effects (font (size 1.27 1.27) (thickness 0.15)) (justify left bottom) hide)
      )
      (property "Datasheet" "https://suddendocs.samtec.com/catalog_english/lshm_dh.pdf" (at 35.56 -10.16 0)
        (effects (font (size 1.27 1.27) (thickness 0.15)) (justify left bottom) hide)
      )
      (property "Manufacturer" "Samtec" (at 35.56 -12.7 0)
        (effects (font (size 1.27 1.27) (thickness 0.15)) (justify left bottom) hide)
      )
      (property "MPN" "LSHM-130-01-L-RH-A-S-K-TR" (at 35.56 -15.24 0)
        (effects (font (size 1.27 1.27) (thickness 0.15)) (justify left bottom) hide)
      )
      (property "Author" "Antmicro" (at 35.56 -17.78 0)
        (effects (font (size 1.27 1.27) (thickness 0.15)) (justify left bottom) hide)
      )
      (property "License" "Apache-2.0" (at 35.56 -20.32 0)
        (effects (font (size 1.27 1.27) (thickness 0.15)) (justify left bottom) hide)
      )
      (symbol "Hermaphroditic_Samtec_LSHM_2x30_LSHM-130-01-L-RH-A-S-K-TR_1_1"
        (rectangle (start 2.54 -81.28) (end 17.78 2.54)
          (stroke (width 0.254) (type default))
          (fill (type background))
        )
        (pin passive line (at 0 0 0) (length 2.54)
          (name "01" (effects (font (size 1.27 1.27))))
          (number "01" (effects (font (size 1.27 1.27))))
        )
        (pin passive line (at 20.32 0 180) (length 2.54)
          (name "02" (effects (font (size 1.27 1.27))))
          (number "02" (effects (font (size 1.27 1.27))))
        )
        (pin passive line (at 0 -2.54 0) (length 2.54)
          (name "03" (effects (font (size 1.27 1.27))))
          (number "03" (effects (font (size 1.27 1.27))))
        )
        (pin passive line (at 20.32 -2.54 180) (length 2.54)
          (name "04" (effects (font (size 1.27 1.27))))
          (number "04" (effects (font (size 1.27 1.27))))
        )
        (pin passive line (at 0 -5.08 0) (length 2.54)
          (name "05" (effects (font (size 1.27 1.27))))
          (number "05" (effects (font (size 1.27 1.27))))
        )
        (pin passive line (at 20.32 -5.08 180) (length 2.54)
          (name "06" (effects (font (size 1.27 1.27))))
          (number "06" (effects (font (size 1.27 1.27))))
        )
        (pin passive line (at 0 -7.62 0) (length 2.54)
          (name "07" (effects (font (size 1.27 1.27))))
          (number "07" (effects (font (size 1.27 1.27))))
        )
        (pin passive line (at 20.32 -7.62 180) (length 2.54)
          (name "08" (effects (font (size 1.27 1.27))))
          (number "08" (effects (font (size 1.27 1.27))))
        )
        (pin passive line (at 0 -10.16 0) (length 2.54)
          (name "09" (effects (font (size 1.27 1.27))))
          (number "09" (effects (font (size 1.27 1.27))))
        )
        (pin passive line (at 20.32 -10.16 180) (length 2.54)
          (name "10" (effects (font (size 1.27 1.27))))
          (number "10" (effects (font (size 1.27 1.27))))
        )
        (pin passive line (at 0 -12.7 0) (length 2.54)
          (name "11" (effects (font (size 1.27 1.27))))
          (number "11" (effects (font (size 1.27 1.27))))
        )
        (pin passive line (at 20.32 -12.7 180) (length 2.54)
          (name "12" (effects (font (size 1.27 1.27))))
          (number "12" (effects (font (size 1.27 1.27))))
        )
        (pin passive line (at 0 -15.24 0) (length 2.54)
          (name "13" (effects (font (size 1.27 1.27))))
          (number "13" (effects (font (size 1.27 1.27))))
        )
        (pin passive line (at 20.32 -15.24 180) (length 2.54)
          (name "14" (effects (font (size 1.27 1.27))))
          (number "14" (effects (font (size 1.27 1.27))))
        )
        (pin passive line (at 0 -17.78 0) (length 2.54)
          (name "15" (effects (font (size 1.27 1.27))))
          (number "15" (effects (font (size 1.27 1.27))))
        )
        (pin passive line (at 20.32 -17.78 180) (length 2.54)
          (name "16" (effects (font (size 1.27 1.27))))
          (number "16" (effects (font (size 1.27 1.27))))
        )
        (pin passive line (at 0 -20.32 0) (length 2.54)
          (name "17" (effects (font (size 1.27 1.27))))
          (number "17" (effects (font (size 1.27 1.27))))
        )
        (pin passive line (at 20.32 -20.32 180) (length 2.54)
          (name "18" (effects (font (size 1.27 1.27))))
          (number "18" (effects (font (size 1.27 1.27))))
        )
        (pin passive line (at 0 -22.86 0) (length 2.54)
          (name "19" (effects (font (size 1.27 1.27))))
          (number "19" (effects (font (size 1.27 1.27))))
        )
        (pin passive line (at 20.32 -22.86 180) (length 2.54)
          (name "20" (effects (font (size 1.27 1.27))))
          (number "20" (effects (font (size 1.27 1.27))))
        )
        (pin passive line (at 0 -25.4 0) (length 2.54)
          (name "21" (effects (font (size 1.27 1.27))))
          (number "21" (effects (font (size 1.27 1.27))))
        )
        (pin passive line (at 20.32 -25.4 180) (length 2.54)
          (name "22" (effects (font (size 1.27 1.27))))
          (number "22" (effects (font (size 1.27 1.27))))
        )
        (pin passive line (at 0 -27.94 0) (length 2.54)
          (name "23" (effects (font (size 1.27 1.27))))
          (number "23" (effects (font (size 1.27 1.27))))
        )
        (pin passive line (at 20.32 -27.94 180) (length 2.54)
          (name "24" (effects (font (size 1.27 1.27))))
          (number "24" (effects (font (size 1.27 1.27))))
        )
        (pin passive line (at 0 -30.48 0) (length 2.54)
          (name "25" (effects (font (size 1.27 1.27))))
          (number "25" (effects (font (size 1.27 1.27))))
        )
        (pin passive line (at 20.32 -30.48 180) (length 2.54)
          (name "26" (effects (font (size 1.27 1.27))))
          (number "26" (effects (font (size 1.27 1.27))))
        )
        (pin passive line (at 0 -33.02 0) (length 2.54)
          (name "27" (effects (font (size 1.27 1.27))))
          (number "27" (effects (font (size 1.27 1.27))))
        )
        (pin passive line (at 20.32 -33.02 180) (length 2.54)
          (name "28" (effects (font (size 1.27 1.27))))
          (number "28" (effects (font (size 1.27 1.27))))
        )
        (pin passive line (at 0 -35.56 0) (length 2.54)
          (name "29" (effects (font (size 1.27 1.27))))
          (number "29" (effects (font (size 1.27 1.27))))
        )
        (pin passive line (at 20.32 -35.56 180) (length 2.54)
          (name "30" (effects (font (size 1.27 1.27))))
          (number "30" (effects (font (size 1.27 1.27))))
        )
        (pin passive line (at 0 -38.1 0) (length 2.54)
          (name "31" (effects (font (size 1.27 1.27))))
          (number "31" (effects (font (size 1.27 1.27))))
        )
        (pin passive line (at 20.32 -38.1 180) (length 2.54)
          (name "32" (effects (font (size 1.27 1.27))))
          (number "32" (effects (font (size 1.27 1.27))))
        )
        (pin passive line (at 0 -40.64 0) (length 2.54)
          (name "33" (effects (font (size 1.27 1.27))))
          (number "33" (effects (font (size 1.27 1.27))))
        )
        (pin passive line (at 20.32 -40.64 180) (length 2.54)
          (name "34" (effects (font (size 1.27 1.27))))
          (number "34" (effects (font (size 1.27 1.27))))
        )
        (pin passive line (at 0 -43.18 0) (length 2.54)
          (name "35" (effects (font (size 1.27 1.27))))
          (number "35" (effects (font (size 1.27 1.27))))
        )
        (pin passive line (at 20.32 -43.18 180) (length 2.54)
          (name "36" (effects (font (size 1.27 1.27))))
          (number "36" (effects (font (size 1.27 1.27))))
        )
        (pin passive line (at 0 -45.72 0) (length 2.54)
          (name "37" (effects (font (size 1.27 1.27))))
          (number "37" (effects (font (size 1.27 1.27))))
        )
        (pin passive line (at 20.32 -45.72 180) (length 2.54)
          (name "38" (effects (font (size 1.27 1.27))))
          (number "38" (effects (font (size 1.27 1.27))))
        )
        (pin passive line (at 0 -48.26 0) (length 2.54)
          (name "39" (effects (font (size 1.27 1.27))))
          (number "39" (effects (font (size 1.27 1.27))))
        )
        (pin passive line (at 20.32 -48.26 180) (length 2.54)
          (name "40" (effects (font (size 1.27 1.27))))
          (number "40" (effects (font (size 1.27 1.27))))
        )
        (pin passive line (at 0 -50.8 0) (length 2.54)
          (name "41" (effects (font (size 1.27 1.27))))
          (number "41" (effects (font (size 1.27 1.27))))
        )
        (pin passive line (at 20.32 -50.8 180) (length 2.54)
          (name "42" (effects (font (size 1.27 1.27))))
          (number "42" (effects (font (size 1.27 1.27))))
        )
        (pin passive line (at 0 -53.34 0) (length 2.54)
          (name "43" (effects (font (size 1.27 1.27))))
          (number "43" (effects (font (size 1.27 1.27))))
        )
        (pin passive line (at 20.32 -53.34 180) (length 2.54)
          (name "44" (effects (font (size 1.27 1.27))))
          (number "44" (effects (font (size 1.27 1.27))))
        )
        (pin passive line (at 0 -55.88 0) (length 2.54)
          (name "45" (effects (font (size 1.27 1.27))))
          (number "45" (effects (font (size 1.27 1.27))))
        )
        (pin passive line (at 20.32 -55.88 180) (length 2.54)
          (name "46" (effects (font (size 1.27 1.27))))
          (number "46" (effects (font (size 1.27 1.27))))
        )
        (pin passive line (at 0 -58.42 0) (length 2.54)
          (name "47" (effects (font (size 1.27 1.27))))
          (number "47" (effects (font (size 1.27 1.27))))
        )
        (pin passive line (at 20.32 -58.42 180) (length 2.54)
          (name "48" (effects (font (size 1.27 1.27))))
          (number "48" (effects (font (size 1.27 1.27))))
        )
        (pin passive line (at 0 -60.96 0) (length 2.54)
          (name "49" (effects (font (size 1.27 1.27))))
          (number "49" (effects (font (size 1.27 1.27))))
        )
        (pin passive line (at 20.32 -60.96 180) (length 2.54)
          (name "50" (effects (font (size 1.27 1.27))))
          (number "50" (effects (font (size 1.27 1.27))))
        )
        (pin passive line (at 0 -63.5 0) (length 2.54)
          (name "51" (effects (font (size 1.27 1.27))))
          (number "51" (effects (font (size 1.27 1.27))))
        )
        (pin passive line (at 20.32 -63.5 180) (length 2.54)
          (name "52" (effects (font (size 1.27 1.27))))
          (number "52" (effects (font (size 1.27 1.27))))
        )
        (pin passive line (at 0 -66.04 0) (length 2.54)
          (name "53" (effects (font (size 1.27 1.27))))
          (number "53" (effects (font (size 1.27 1.27))))
        )
        (pin passive line (at 20.32 -66.04 180) (length 2.54)
          (name "54" (effects (font (size 1.27 1.27))))
          (number "54" (effects (font (size 1.27 1.27))))
        )
        (pin passive line (at 0 -68.58 0) (length 2.54)
          (name "55" (effects (font (size 1.27 1.27))))
          (number "55" (effects (font (size 1.27 1.27))))
        )
        (pin passive line (at 20.32 -68.58 180) (length 2.54)
          (name "56" (effects (font (size 1.27 1.27))))
          (number "56" (effects (font (size 1.27 1.27))))
        )
        (pin passive line (at 0 -71.12 0) (length 2.54)
          (name "57" (effects (font (size 1.27 1.27))))
          (number "57" (effects (font (size 1.27 1.27))))
        )
        (pin passive line (at 20.32 -71.12 180) (length 2.54)
          (name "58" (effects (font (size 1.27 1.27))))
          (number "58" (effects (font (size 1.27 1.27))))
        )
        (pin passive line (at 0 -73.66 0) (length 2.54)
          (name "59" (effects (font (size 1.27 1.27))))
          (number "59" (effects (font (size 1.27 1.27))))
        )
        (pin passive line (at 20.32 -73.66 180) (length 2.54)
          (name "60" (effects (font (size 1.27 1.27))))
          (number "60" (effects (font (size 1.27 1.27))))
        )
        (pin passive line (at 20.32 -78.74 180) (length 2.54)
          (name "SHIELD" (effects (font (size 1.27 1.27))))
          (number "S1" (effects (font (size 1.27 1.27))))
        )
        (pin passive line (at 20.32 -78.74 180) (length 2.54) hide
          (name "SHIELD" (effects (font (size 1.27 1.27))))
          (number "S2" (effects (font (size 1.27 1.27))))
        )
      )
    )
	(symbol "scalenode-cm4-baseboard:JST_XH_1x2_B2B-XH-A-LF-SN" (in_bom yes) (on_board yes)
      (property "Reference" "J" (at 7.62 1.27 0)
        (effects (font (size 1.27 1.27) (thickness 0.15)) (justify left bottom))
      )
      (property "Value" "JST_XH_1x2_B2B-XH-A-LF-SN" (at 7.62 -1.27 0)
        (effects (font (size 1.27 1.27) (thickness 0.15)) (justify left bottom) hide)
      )
      (property "Footprint" "scalenode-cm4-baseboard-footprints:Conn_JST_XH_1x2_B2B-XH-A-LF-SN" (at 7.62 -3.81 0)
        (effects (font (size 1.27 1.27) (thickness 0.15)) (justify left bottom) hide)
      )
      (property "Datasheet" "http://www.jst-mfg.com/product/pdf/eng/eXH.pdf" (at 7.62 -6.35 0)
        (effects (font (size 1.27 1.27) (thickness 0.15)) (justify left bottom) hide)
      )
      (property "MPN" "B2B-XH-A(LF)(SN)" (at 7.62 -8.89 0)
        (effects (font (size 1.27 1.27) (thickness 0.15)) (justify left bottom))
      )
      (property "Manufacturer" "JST Automotive Connectors" (at 7.62 -11.43 0)
        (effects (font (size 1.27 1.27) (thickness 0.15)) (justify left bottom) hide)
      )
      (property "Author" "Antmicro" (at 7.62 -13.97 0)
        (effects (font (size 1.27 1.27) (thickness 0.15)) (justify left bottom) hide)
      )
      (property "License" "Apache-2.0" (at 7.62 -16.51 0)
        (effects (font (size 1.27 1.27) (thickness 0.15)) (justify left bottom) hide)
      )
      (property "ki_keywords" "CONNECTOR, THT" (at 0 0 0)
        (effects (font (size 1.27 1.27)) hide)
      )
      (property "ki_description" "Rectangular connector, header" (at 0 0 0)
        (effects (font (size 1.27 1.27)) hide)
      )
      (symbol "JST_XH_1x2_B2B-XH-A-LF-SN_1_1"
        (rectangle (start 2.54 -2.413) (end 3.81 -2.667)
          (stroke (width 0.254) (type default))
          (fill (type background))
        )
        (rectangle (start 2.54 0.127) (end 3.81 -0.127)
          (stroke (width 0.254) (type default))
          (fill (type background))
        )
        (rectangle (start 5.08 -3.81) (end 2.54 1.27)
          (stroke (width 0.254) (type default))
          (fill (type background))
        )
        (pin passive line (at 0 0 0) (length 2.54)
          (name "~" (effects (font (size 1.27 1.27))))
          (number "1" (effects (font (size 1.27 1.27))))
        )
        (pin passive line (at 0 -2.54 0) (length 2.54)
          (name "~" (effects (font (size 1.27 1.27))))
          (number "2" (effects (font (size 1.27 1.27))))
        )
      )
    )
	(symbol "scalenode-cm4-baseboard:LED_G_0603_598-8D80-107F" (pin_names hide) (in_bom yes) (on_board yes)
      (property "Reference" "D" (at 22.86 -2.54 0)
        (effects (font (size 1.27 1.27) (thickness 0.15)) (justify left bottom))
      )
      (property "Value" "LED_G_0603_598-8D80-107F" (at 22.86 -5.08 0)
        (effects (font (size 1.27 1.27) (thickness 0.15)) (justify left bottom))
      )
      (property "Footprint" "scalenode-cm4-baseboard-footprints:LED_0603_1608Metric_G" (at 22.86 -7.62 0)
        (effects (font (size 1.27 1.27) (thickness 0.15)) (justify left bottom) hide)
      )
      (property "Datasheet" "https://www.farnell.com/datasheets/3093797.pdf" (at 22.86 -10.16 0)
        (effects (font (size 1.27 1.27) (thickness 0.15)) (justify left bottom) hide)
      )
      (property "MPN" "598-8D80-107F" (at 22.86 -12.7 0)
        (effects (font (size 1.27 1.27) (thickness 0.15)) (justify left bottom) hide)
      )
      (property "Manufacturer" "Dialight" (at 22.86 -15.24 0)
        (effects (font (size 1.27 1.27) (thickness 0.15)) (justify left bottom) hide)
      )
      (property "Author" "Antmicro" (at 22.86 -17.78 0)
        (effects (font (size 1.27 1.27) (thickness 0.15)) (justify left bottom) hide)
      )
      (property "License" "Apache-2.0" (at 22.86 -20.32 0)
        (effects (font (size 1.27 1.27) (thickness 0.15)) (justify left bottom) hide)
      )
      (symbol "LED_G_0603_598-8D80-107F_1_1"
        (polyline
          (pts
            (xy 4.445 3.81)
            (xy 3.175 2.54)
          )
          (stroke (width 0.254) (type default))
          (fill (type none))
        )
        (polyline
          (pts
            (xy 5.08 1.27)
            (xy 5.08 -1.27)
          )
          (stroke (width 0.254) (type default))
          (fill (type none))
        )
        (polyline
          (pts
            (xy 5.715 3.175)
            (xy 4.445 1.905)
          )
          (stroke (width 0.254) (type default))
          (fill (type none))
        )
        (polyline
          (pts
            (xy 3.81 3.81)
            (xy 4.445 3.81)
            (xy 4.445 3.175)
          )
          (stroke (width 0.254) (type default))
          (fill (type none))
        )
        (polyline
          (pts
            (xy 5.08 3.175)
            (xy 5.715 3.175)
            (xy 5.715 2.54)
          )
          (stroke (width 0.254) (type default))
          (fill (type none))
        )
        (polyline
          (pts
            (xy 2.54 1.27)
            (xy 2.54 -1.27)
            (xy 5.08 0)
            (xy 2.54 1.27)
          )
          (stroke (width 0.254) (type default))
          (fill (type none))
        )
        (pin passive line (at 0 0 0) (length 2.54)
          (name "1" (effects (font (size 1.27 1.27))))
          (number "1" (effects (font (size 1.27 1.27))))
        )
        (pin passive line (at 7.62 0 180) (length 2.54)
          (name "2" (effects (font (size 1.27 1.27))))
          (number "2" (effects (font (size 1.27 1.27))))
        )
      )
    )
	(symbol "scalenode-cm4-baseboard:LED_G_0603_KP-1608CGCK" (pin_names hide) (in_bom yes) (on_board yes)
      (property "Reference" "D" (at 22.86 -5.08 0)
        (effects (font (size 1.27 1.27) (thickness 0.15)) (justify left bottom))
      )
      (property "Value" "LED_G_0603_KP-1608CGCK" (at 22.86 -7.62 0)
        (effects (font (size 1.27 1.27) (thickness 0.15)) (justify left bottom))
      )
      (property "Footprint" "scalenode-cm4-baseboard-footprints:LED_0603_1608Metric_G" (at 22.86 -10.16 0)
        (effects (font (size 1.27 1.27) (thickness 0.15)) (justify left bottom) hide)
      )
      (property "Datasheet" "http://www.farnell.com/datasheets/2045956.pdf" (at 22.86 -12.7 0)
        (effects (font (size 1.27 1.27) (thickness 0.15)) (justify left bottom) hide)
      )
      (property "MPN" "KP-1608CGCK" (at 22.86 -15.24 0)
        (effects (font (size 1.27 1.27) (thickness 0.15)) (justify left bottom) hide)
      )
      (property "Manufacturer" "Kingbright" (at 22.86 -17.78 0)
        (effects (font (size 1.27 1.27) (thickness 0.15)) (justify left bottom) hide)
      )
      (property "Author" "Antmicro" (at 22.86 -20.32 0)
        (effects (font (size 1.27 1.27) (thickness 0.15)) (justify left bottom) hide)
      )
      (property "License" "Apache-2.0" (at 22.86 -22.86 0)
        (effects (font (size 1.27 1.27) (thickness 0.15)) (justify left bottom) hide)
      )
      (symbol "LED_G_0603_KP-1608CGCK_1_1"
        (polyline
          (pts
            (xy 5.08 1.27)
            (xy 5.08 -1.27)
          )
          (stroke (width 0.254) (type default))
          (fill (type none))
        )
        (polyline
          (pts
            (xy 2.54 1.27)
            (xy 2.54 -1.27)
            (xy 5.08 0)
            (xy 2.54 1.27)
          )
          (stroke (width 0.254) (type default))
          (fill (type outline))
        )
        (polyline
          (pts
            (xy 3.683 2.286)
            (xy 3.683 1.778)
            (xy 3.683 2.286)
            (xy 3.175 2.286)
            (xy 3.683 2.286)
            (xy 2.794 1.397)
          )
          (stroke (width 0.254) (type default))
          (fill (type none))
        )
        (polyline
          (pts
            (xy 4.699 2.032)
            (xy 4.699 1.524)
            (xy 4.699 2.032)
            (xy 4.191 2.032)
            (xy 4.699 2.032)
            (xy 3.683 1.016)
          )
          (stroke (width 0.254) (type default))
          (fill (type none))
        )
        (pin passive line (at 0 0 0) (length 2.54)
          (name "1" (effects (font (size 1.27 1.27))))
          (number "1" (effects (font (size 1.27 1.27))))
        )
        (pin passive line (at 7.62 0 180) (length 2.54)
          (name "2" (effects (font (size 1.27 1.27))))
          (number "2" (effects (font (size 1.27 1.27))))
        )
      )
    )
	(symbol "scalenode-cm4-baseboard:L_1u_5.5A_Bourns-SRP3212A" (pin_names hide) (in_bom yes) (on_board yes)
      (property "Reference" "L" (at 11.43 -5.08 0)
        (effects (font (size 1.27 1.27) (thickness 0.15)) (justify left bottom))
      )
      (property "Value" "L_1u_5.5A_Bourns-SRP3212A" (at 11.43 -7.62 0)
        (effects (font (size 1.27 1.27) (thickness 0.15)) (justify left bottom))
      )
      (property "Footprint" "scalenode-cm4-baseboard-footprints:L_Bourns-SRP3212A" (at 11.43 -12.7 0)
        (effects (font (size 1.27 1.27) (thickness 0.15)) (justify left bottom) hide)
      )
      (property "Datasheet" "https://www.mouser.com/datasheet/2/54/SRP3212A-3011944.pdf" (at 11.43 -15.24 0)
        (effects (font (size 1.27 1.27) (thickness 0.15)) (justify left bottom) hide)
      )
      (property "Manufacturer" "Bourns" (at 11.43 -17.78 0)
        (effects (font (size 1.27 1.27) (thickness 0.15)) (justify left bottom) hide)
      )
      (property "MPN" "SRP3212A-1R0M" (at 11.43 -20.32 0)
        (effects (font (size 1.27 1.27) (thickness 0.15)) (justify left bottom) hide)
      )
      (property "MaxCur" "5.5A" (at 11.43 -22.86 0)
        (effects (font (size 1.27 1.27) (thickness 0.15)) (justify left bottom) hide)
      )
      (property "Size" "3.2x2.5" (at 11.43 -25.4 0)
        (effects (font (size 1.27 1.27) (thickness 0.15)) (justify left bottom) hide)
      )
      (property "Val" "1u/5.5A" (at 11.43 -10.16 0)
        (effects (font (size 1.27 1.27) (thickness 0.15)) (justify left bottom))
      )
      (property "Author" "Antmicro" (at 11.43 -27.94 0)
        (effects (font (size 1.27 1.27) (thickness 0.15)) (justify left bottom) hide)
      )
      (property "License" "Apache-2.0" (at 11.43 -30.48 0)
        (effects (font (size 1.27 1.27) (thickness 0.15)) (justify left bottom) hide)
      )
      (property "ki_keywords" "SMT, INDUCTOR, PASSIVE" (at 0 0 0)
        (effects (font (size 1.27 1.27)) hide)
      )
      (property "ki_description" "Power Inductor (SMD), 1 µH, 5.5 A, Shielded, 6.5 A, SRP3212 Series" (at 0 0 0)
        (effects (font (size 1.27 1.27)) hide)
      )
      (symbol "L_1u_5.5A_Bourns-SRP3212A_1_1"
        (arc (start 2.8702 0.5334) (mid 2.6436 0.3084) (end 2.54 0)
          (stroke (width 0.254) (type default))
          (fill (type none))
        )
        (arc (start 3.5052 0.5334) (mid 3.186 0.6272) (end 2.8702 0.5334)
          (stroke (width 0.254) (type default))
          (fill (type none))
        )
        (arc (start 3.81 0) (mid 3.7297 0.309) (end 3.5052 0.5334)
          (stroke (width 0.254) (type default))
          (fill (type none))
        )
        (arc (start 4.1402 0.5334) (mid 3.9136 0.3084) (end 3.81 0)
          (stroke (width 0.254) (type default))
          (fill (type none))
        )
        (arc (start 4.7752 0.5334) (mid 4.456 0.6272) (end 4.1402 0.5334)
          (stroke (width 0.254) (type default))
          (fill (type none))
        )
        (arc (start 5.08 0) (mid 4.9997 0.309) (end 4.7752 0.5334)
          (stroke (width 0.254) (type default))
          (fill (type none))
        )
        (arc (start 5.4102 0.5334) (mid 5.1836 0.3084) (end 5.1054 0)
          (stroke (width 0.254) (type default))
          (fill (type none))
        )
        (arc (start 6.0452 0.5334) (mid 5.726 0.6272) (end 5.4102 0.5334)
          (stroke (width 0.254) (type default))
          (fill (type none))
        )
        (arc (start 6.3246 -0.0508) (mid 6.2613 0.2752) (end 6.0452 0.5334)
          (stroke (width 0.254) (type default))
          (fill (type none))
        )
        (arc (start 6.6548 0.5334) (mid 6.437 0.3053) (end 6.35 0)
          (stroke (width 0.254) (type default))
          (fill (type none))
        )
        (arc (start 7.2898 0.5334) (mid 6.9742 0.6142) (end 6.6548 0.5334)
          (stroke (width 0.254) (type default))
          (fill (type none))
        )
        (arc (start 7.5946 0) (mid 7.5122 0.306) (end 7.2898 0.5334)
          (stroke (width 0.254) (type default))
          (fill (type none))
        )
        (pin passive line (at 0 0 0) (length 2.54)
          (name "1" (effects (font (size 1.27 1.27))))
          (number "1" (effects (font (size 1.27 1.27))))
        )
        (pin passive line (at 10.16 0 180) (length 2.54)
          (name "2" (effects (font (size 1.27 1.27))))
          (number "2" (effects (font (size 1.27 1.27))))
        )
      )
    )
	(symbol "scalenode-cm4-baseboard:MB10S" (pin_names hide) (in_bom yes) (on_board yes)
      (property "Reference" "D" (at 27.94 -2.54 0)
        (effects (font (size 1.27 1.27) (thickness 0.15)) (justify left bottom))
      )
      (property "Value" "MB10S" (at 27.94 -5.08 0)
        (effects (font (size 1.27 1.27) (thickness 0.15)) (justify left bottom) hide)
      )
      (property "Footprint" "scalenode-cm4-baseboard-footprints:SOIC-4_W3.9mm" (at 27.94 -7.62 0)
        (effects (font (size 1.27 1.27) (thickness 0.15)) (justify left bottom) hide)
      )
      (property "Datasheet" "http://www.farnell.com/datasheets/2895435.pdf" (at 27.94 -10.16 0)
        (effects (font (size 1.27 1.27) (thickness 0.15)) (justify left bottom) hide)
      )
      (property "MPN" "MB10S" (at 27.94 -12.7 0)
        (effects (font (size 1.27 1.27) (thickness 0.15)) (justify left bottom))
      )
      (property "Manufacturer" "Multicomp Pro" (at 27.94 -15.24 0)
        (effects (font (size 1.27 1.27) (thickness 0.15)) (justify left bottom) hide)
      )
      (property "Author" "Antmicro" (at 27.94 -17.78 0)
        (effects (font (size 1.27 1.27) (thickness 0.15)) (justify left bottom) hide)
      )
      (property "License" "Apache-2.0" (at 27.94 -20.32 0)
        (effects (font (size 1.27 1.27) (thickness 0.15)) (justify left bottom) hide)
      )
      (property "ki_description" "TVS diode" (at 0 0 0)
        (effects (font (size 1.27 1.27)) hide)
      )
      (symbol "MB10S_1_1"
        (polyline
          (pts
            (xy 2.54 -5.08)
            (xy 3.81 -5.08)
          )
          (stroke (width 0.254) (type default))
          (fill (type none))
        )
        (polyline
          (pts
            (xy 3.81 -10.16)
            (xy 2.54 -10.16)
          )
          (stroke (width 0.254) (type default))
          (fill (type none))
        )
        (polyline
          (pts
            (xy 3.81 -3.81)
            (xy 3.81 -7.62)
          )
          (stroke (width 0.254) (type default))
          (fill (type none))
        )
        (polyline
          (pts
            (xy 3.81 -2.54)
            (xy 3.81 -3.81)
          )
          (stroke (width 0.254) (type default))
          (fill (type none))
        )
        (polyline
          (pts
            (xy 3.81 0)
            (xy 2.54 0)
          )
          (stroke (width 0.254) (type default))
          (fill (type none))
        )
        (polyline
          (pts
            (xy 5.08 -7.62)
            (xy 3.81 -7.62)
          )
          (stroke (width 0.254) (type default))
          (fill (type none))
        )
        (polyline
          (pts
            (xy 5.08 -2.54)
            (xy 3.81 -2.54)
          )
          (stroke (width 0.254) (type default))
          (fill (type none))
        )
        (polyline
          (pts
            (xy 7.62 -6.35)
            (xy 7.62 -8.89)
          )
          (stroke (width 0.254) (type default))
          (fill (type none))
        )
        (polyline
          (pts
            (xy 7.62 -1.27)
            (xy 7.62 -3.81)
          )
          (stroke (width 0.254) (type default))
          (fill (type none))
        )
        (polyline
          (pts
            (xy 8.89 -7.62)
            (xy 7.62 -7.62)
          )
          (stroke (width 0.254) (type default))
          (fill (type none))
        )
        (polyline
          (pts
            (xy 8.89 -2.54)
            (xy 7.62 -2.54)
          )
          (stroke (width 0.254) (type default))
          (fill (type none))
        )
        (polyline
          (pts
            (xy 10.16 -7.62)
            (xy 7.62 -7.62)
          )
          (stroke (width 0.254) (type default))
          (fill (type none))
        )
        (polyline
          (pts
            (xy 10.16 -2.54)
            (xy 7.62 -2.54)
          )
          (stroke (width 0.254) (type default))
          (fill (type none))
        )
        (polyline
          (pts
            (xy 12.7 -7.62)
            (xy 13.97 -7.62)
          )
          (stroke (width 0.254) (type default))
          (fill (type none))
        )
        (polyline
          (pts
            (xy 12.7 -6.35)
            (xy 12.7 -8.89)
          )
          (stroke (width 0.254) (type default))
          (fill (type none))
        )
        (polyline
          (pts
            (xy 12.7 -2.54)
            (xy 13.97 -2.54)
          )
          (stroke (width 0.254) (type default))
          (fill (type none))
        )
        (polyline
          (pts
            (xy 12.7 -1.27)
            (xy 12.7 -3.81)
          )
          (stroke (width 0.254) (type default))
          (fill (type none))
        )
        (polyline
          (pts
            (xy 13.97 -5.08)
            (xy 15.24 -5.08)
          )
          (stroke (width 0.254) (type default))
          (fill (type none))
        )
        (polyline
          (pts
            (xy 13.97 -3.81)
            (xy 13.97 -7.62)
          )
          (stroke (width 0.254) (type default))
          (fill (type none))
        )
        (polyline
          (pts
            (xy 13.97 -2.54)
            (xy 13.97 -3.81)
          )
          (stroke (width 0.254) (type default))
          (fill (type none))
        )
        (polyline
          (pts
            (xy 8.89 -7.62)
            (xy 8.89 -10.16)
            (xy 3.81 -10.16)
          )
          (stroke (width 0.254) (type default))
          (fill (type none))
        )
        (polyline
          (pts
            (xy 8.89 -2.54)
            (xy 8.89 0)
            (xy 3.81 0)
          )
          (stroke (width 0.254) (type default))
          (fill (type none))
        )
        (polyline
          (pts
            (xy 5.08 -6.35)
            (xy 5.08 -8.89)
            (xy 7.62 -7.62)
            (xy 5.08 -6.35)
          )
          (stroke (width 0.254) (type default))
          (fill (type outline))
        )
        (polyline
          (pts
            (xy 5.08 -1.27)
            (xy 5.08 -3.81)
            (xy 7.62 -2.54)
            (xy 5.08 -1.27)
          )
          (stroke (width 0.254) (type default))
          (fill (type outline))
        )
        (polyline
          (pts
            (xy 10.16 -6.35)
            (xy 10.16 -8.89)
            (xy 12.7 -7.62)
            (xy 10.16 -6.35)
          )
          (stroke (width 0.254) (type default))
          (fill (type outline))
        )
        (polyline
          (pts
            (xy 10.16 -1.27)
            (xy 10.16 -3.81)
            (xy 12.7 -2.54)
            (xy 10.16 -1.27)
          )
          (stroke (width 0.254) (type default))
          (fill (type outline))
        )
        (rectangle (start 2.54 1.27) (end 15.24 -11.43)
          (stroke (width 0.254) (type default))
          (fill (type background))
        )
        (pin passive line (at 17.78 -5.08 180) (length 2.54)
          (name "1" (effects (font (size 1.27 1.27))))
          (number "1" (effects (font (size 1.27 1.27))))
        )
        (pin passive line (at 0 -5.08 0) (length 2.54)
          (name "2" (effects (font (size 1.27 1.27))))
          (number "2" (effects (font (size 1.27 1.27))))
        )
        (pin passive line (at 0 0 0) (length 2.54)
          (name "3" (effects (font (size 1.27 1.27))))
          (number "3" (effects (font (size 1.27 1.27))))
        )
        (pin passive line (at 0 -10.16 0) (length 2.54)
          (name "4" (effects (font (size 1.27 1.27))))
          (number "4" (effects (font (size 1.27 1.27))))
        )
      )
    )
	(symbol "scalenode-cm4-baseboard:MP_Pad4.5mm_Drill2.2mm" (pin_names hide) (in_bom no) (on_board yes)
      (property "Reference" "MP" (at 17.78 -2.54 0)
        (effects (font (size 1.27 1.27) (thickness 0.15)) (justify left bottom))
      )
      (property "Value" "MP_Pad4.5mm_Drill2.2mm" (at 17.78 -5.08 0)
        (effects (font (size 1.27 1.27) (thickness 0.15)) (justify left bottom))
      )
      (property "Footprint" "scalenode-cm4-baseboard-footprints:MP_Pad4.5mm_Drill2.2mm" (at 17.78 -7.62 0)
        (effects (font (size 1.27 1.27) (thickness 0.15)) (justify left bottom) hide)
      )
      (property "Datasheet" "" (at 16.84 -15.57 0)
        (effects (font (size 1.27 1.27) (thickness 0.15)) (justify left bottom) hide)
      )
      (property "Author" "Antmicro" (at 17.78 -12.7 0)
        (effects (font (size 1.27 1.27) (thickness 0.15)) (justify left bottom) hide)
      )
      (property "License" "Apache-2.0" (at 17.78 -15.24 0)
        (effects (font (size 1.27 1.27) (thickness 0.15)) (justify left bottom) hide)
      )
      (property "ki_keywords" "MECHANICAL" (at 0 0 0)
        (effects (font (size 1.27 1.27)) hide)
      )
      (property "ki_description" "Mechanical part" (at 0 0 0)
        (effects (font (size 1.27 1.27)) hide)
      )
      (symbol "MP_Pad4.5mm_Drill2.2mm_1_1"
        (circle (center 5.08 0) (radius 1.27)
          (stroke (width 0.254) (type default))
          (fill (type background))
        )
        (circle (center 5.08 0) (radius 2.54)
          (stroke (width 0.254) (type default))
          (fill (type background))
        )
        (pin passive line (at 0 0 0) (length 2.54)
          (name "~" (effects (font (size 1.27 1.27))))
          (number "1" (effects (font (size 1.27 1.27))))
        )
      )
    )
	(symbol "scalenode-cm4-baseboard:MP_Pad6.2mm_Drill2.75mm" (pin_names hide) (in_bom no) (on_board yes)
      (property "Reference" "MP" (at 15.24 -5.08 0)
        (effects (font (size 1.27 1.27) (thickness 0.15)) (justify left bottom))
      )
      (property "Value" "MP_Pad6.2mm_Drill2.75mm" (at 15.24 -7.62 0)
        (effects (font (size 1.27 1.27) (thickness 0.15)) (justify left bottom))
      )
      (property "Footprint" "scalenode-cm4-baseboard-footprints:MP_Pad6.2mm_Drill2.75mm" (at 15.24 -10.16 0)
        (effects (font (size 1.27 1.27) (thickness 0.15)) (justify left bottom) hide)
      )
      (property "Datasheet" "" (at 16.84 -15.57 0)
        (effects (font (size 1.27 1.27) (thickness 0.15)) (justify left bottom) hide)
      )
      (property "Author" "Antmicro" (at 15.24 -12.7 0)
        (effects (font (size 1.27 1.27) (thickness 0.15)) (justify left bottom) hide)
      )
      (property "License" "Apache-2.0" (at 15.24 -15.24 0)
        (effects (font (size 1.27 1.27) (thickness 0.15)) (justify left bottom) hide)
      )
      (property "ki_keywords" "MECHANICAL" (at 0 0 0)
        (effects (font (size 1.27 1.27)) hide)
      )
      (property "ki_description" "Mechanical part" (at 0 0 0)
        (effects (font (size 1.27 1.27)) hide)
      )
      (symbol "MP_Pad6.2mm_Drill2.75mm_1_1"
        (circle (center 5.08 0) (radius 1.27)
          (stroke (width 0.254) (type default))
          (fill (type background))
        )
        (circle (center 5.08 0) (radius 2.54)
          (stroke (width 0.254) (type default))
          (fill (type background))
        )
        (pin passive line (at 0 0 0) (length 2.54)
          (name "~" (effects (font (size 1.27 1.27))))
          (number "1" (effects (font (size 1.27 1.27))))
        )
      )
    )
	(symbol "scalenode-cm4-baseboard:MicroSD_1140084168" (in_bom yes) (on_board yes)
      (property "Reference" "J" (at 38.1 -3.81 0)
        (effects (font (size 1.27 1.27) (thickness 0.15)) (justify left bottom))
      )
      (property "Value" "MicroSD_1140084168" (at 38.1 -6.35 0)
        (effects (font (size 1.27 1.27) (thickness 0.15)) (justify left bottom))
      )
      (property "Footprint" "scalenode-cm4-baseboard-footprints:MicroSD_Amphenol_1140084168" (at 38.1 -8.89 0)
        (effects (font (size 1.27 1.27) (thickness 0.15)) (justify left bottom) hide)
      )
      (property "Datasheet" "https://cdn.amphenol-cs.com/media/wysiwyg/files/documentation/datasheet/inputoutput/io_micro_sdcard.pdf" (at 38.1 -11.43 0)
        (effects (font (size 1.27 1.27) (thickness 0.15)) (justify left bottom) hide)
      )
      (property "MPN" "1140084168" (at 38.1 -13.97 0)
        (effects (font (size 1.27 1.27) (thickness 0.15)) (justify left bottom) hide)
      )
      (property "Manufacturer" "Amphenol" (at 38.1 -16.51 0)
        (effects (font (size 1.27 1.27) (thickness 0.15)) (justify left bottom) hide)
      )
      (property "Author" "Antmicro" (at 38.1 -19.05 0)
        (effects (font (size 1.27 1.27) (thickness 0.15)) (justify left bottom) hide)
      )
      (property "License" "Apache-2.0" (at 38.1 -21.59 0)
        (effects (font (size 1.27 1.27) (thickness 0.15)) (justify left bottom) hide)
      )
      (property "ki_description" "Memory Card Connector, MicroSD, Push-Pull, 8 Contacts, Copper Alloy, Gold Plated Contacts" (at 0 0 0)
        (effects (font (size 1.27 1.27)) hide)
      )
      (symbol "MicroSD_1140084168_1_1"
        (polyline
          (pts
            (xy 2.54 2.54)
            (xy 2.54 -24.13)
            (xy 10.16 -24.13)
            (xy 13.97 -24.13)
            (xy 19.05 -24.13)
            (xy 19.05 -16.51)
            (xy 24.13 -11.43)
            (xy 24.13 2.54)
            (xy 2.54 2.54)
          )
          (stroke (width 0.254) (type default))
          (fill (type background))
        )
        (text "microSD CARD" (at 19.05 -12.7 900)
          (effects (font (size 1.27 1.27) (thickness 0.15)) (justify left bottom))
        )
        (pin bidirectional line (at 0 0 0) (length 2.54)
          (name "DAT2" (effects (font (size 1.27 1.27))))
          (number "1" (effects (font (size 1.27 1.27))))
        )
        (pin passive line (at 0 -22.86 0) (length 2.54)
          (name "CD2" (effects (font (size 1.27 1.27))))
          (number "10" (effects (font (size 1.27 1.27))))
        )
        (pin bidirectional line (at 0 -2.54 0) (length 2.54)
          (name "CD/DAT3" (effects (font (size 1.27 1.27))))
          (number "2" (effects (font (size 1.27 1.27))))
        )
        (pin bidirectional line (at 0 -5.08 0) (length 2.54)
          (name "CMD" (effects (font (size 1.27 1.27))))
          (number "3" (effects (font (size 1.27 1.27))))
        )
        (pin power_in line (at 0 -7.62 0) (length 2.54)
          (name "VDD" (effects (font (size 1.27 1.27))))
          (number "4" (effects (font (size 1.27 1.27))))
        )
        (pin output line (at 0 -10.16 0) (length 2.54)
          (name "CLK" (effects (font (size 1.27 1.27))))
          (number "5" (effects (font (size 1.27 1.27))))
        )
        (pin power_in line (at 0 -12.7 0) (length 2.54)
          (name "VSS" (effects (font (size 1.27 1.27))))
          (number "6" (effects (font (size 1.27 1.27))))
        )
        (pin bidirectional line (at 0 -15.24 0) (length 2.54)
          (name "DAT0" (effects (font (size 1.27 1.27))))
          (number "7" (effects (font (size 1.27 1.27))))
        )
        (pin bidirectional line (at 0 -17.78 0) (length 2.54)
          (name "DAT1" (effects (font (size 1.27 1.27))))
          (number "8" (effects (font (size 1.27 1.27))))
        )
        (pin passive line (at 0 -20.32 0) (length 2.54)
          (name "CD1" (effects (font (size 1.27 1.27))))
          (number "9" (effects (font (size 1.27 1.27))))
        )
        (pin passive line (at 21.59 -20.32 180) (length 2.54)
          (name "Shell" (effects (font (size 1.27 1.27))))
          (number "SH" (effects (font (size 1.27 1.27))))
        )
      )
    )
	(symbol "scalenode-cm4-baseboard:PDQE30-Q48-S5-D" (in_bom yes) (on_board yes)
      (property "Reference" "U" (at 35.56 -2.54 0)
        (effects (font (size 1.27 1.27) (thickness 0.15)) (justify left bottom))
      )
      (property "Value" "PDQE30-Q48-S5-D" (at 35.56 -7.62 0)
        (effects (font (size 1.27 1.27) (thickness 0.15)) (justify left bottom) hide)
      )
      (property "Footprint" "scalenode-cm4-baseboard-footprints:CONV_PDQE30-Q48-S5-D" (at 35.56 -10.16 0)
        (effects (font (size 1.27 1.27) (thickness 0.15)) (justify left bottom) hide)
      )
      (property "Datasheet" "https://www.cui.com/product/resource/pdqe30-d.pdf" (at 35.56 -12.7 0)
        (effects (font (size 1.27 1.27) (thickness 0.15)) (justify left bottom) hide)
      )
      (property "MPN" "PDQE30-Q48-S5-D" (at 35.56 -5.08 0)
        (effects (font (size 1.27 1.27) (thickness 0.15)) (justify left bottom))
      )
      (property "Manufacturer" "CUI Inc" (at 35.56 -15.24 0)
        (effects (font (size 1.27 1.27) (thickness 0.15)) (justify left bottom) hide)
      )
      (property "Author" "Antmicro" (at 35.56 -17.78 0)
        (effects (font (size 1.27 1.27) (thickness 0.15)) (justify left bottom) hide)
      )
      (property "License" "Apache-2.0" (at 35.56 -20.32 0)
        (effects (font (size 1.27 1.27) (thickness 0.15)) (justify left bottom) hide)
      )
      (property "ki_keywords" "THT, PMIC, IC, DC-DC, CONVERTER" (at 0 0 0)
        (effects (font (size 1.27 1.27)) hide)
      )
      (property "ki_description" "Isolated Through Hole DC/DC Converter, ITE, 4:1, 30 W, 1 Output, 5 V, 6 A" (at 0 0 0)
        (effects (font (size 1.27 1.27)) hide)
      )
      (symbol "PDQE30-Q48-S5-D_1_1"
        (rectangle (start 2.54 2.54) (end 17.78 -17.78)
          (stroke (width 0.254) (type default))
          (fill (type background))
        )
        (pin input line (at 0 -7.62 0) (length 2.54)
          (name "CTRL" (effects (font (size 1.27 1.27))))
          (number "1" (effects (font (size 1.27 1.27))))
        )
        (pin power_in line (at 0 -15.24 0) (length 2.54)
          (name "GND" (effects (font (size 1.27 1.27))))
          (number "2" (effects (font (size 1.27 1.27))))
        )
        (pin power_in line (at 0 0 0) (length 2.54)
          (name "V_{IN}" (effects (font (size 1.27 1.27))))
          (number "3" (effects (font (size 1.27 1.27))))
        )
        (pin power_out line (at 20.32 0 180) (length 2.54)
          (name "V_{O}" (effects (font (size 1.27 1.27))))
          (number "4" (effects (font (size 1.27 1.27))))
        )
        (pin passive line (at 20.32 -7.62 180) (length 2.54)
          (name "TRIM" (effects (font (size 1.27 1.27))))
          (number "5" (effects (font (size 1.27 1.27))))
        )
        (pin power_out line (at 20.32 -15.24 180) (length 2.54)
          (name "0V" (effects (font (size 1.27 1.27))))
          (number "6" (effects (font (size 1.27 1.27))))
        )
      )
    )
	(symbol "scalenode-cm4-baseboard:PTC_4.5A_1206" (pin_numbers hide) (pin_names hide) (in_bom yes) (on_board yes)
      (property "Reference" "F" (at 13.97 0 0)
        (effects (font (size 1.27 1.27) (thickness 0.15)) (justify left bottom))
      )
      (property "Value" "PTC_4.5A_1206" (at 13.97 -2.54 0)
        (effects (font (size 1.27 1.27) (thickness 0.15)) (justify left bottom) hide)
      )
      (property "Footprint" "scalenode-cm4-baseboard-footprints:F_1206_3216Metric" (at 13.97 -5.08 0)
        (effects (font (size 1.27 1.27) (thickness 0.15)) (justify left bottom) hide)
      )
      (property "Datasheet" "http://www.farnell.com/datasheets/2282556.pdf" (at 13.97 -7.62 0)
        (effects (font (size 1.27 1.27) (thickness 0.15)) (justify left bottom) hide)
      )
      (property "MPN" "1206L450SLWR" (at 13.97 -10.16 0)
        (effects (font (size 1.27 1.27) (thickness 0.15)) (justify left bottom))
      )
      (property "Manufacturer" "Littelfuse" (at 13.97 -12.7 0)
        (effects (font (size 1.27 1.27) (thickness 0.15)) (justify left bottom) hide)
      )
      (property "Author" "Antmicro" (at 13.97 -15.24 0)
        (effects (font (size 1.27 1.27) (thickness 0.15)) (justify left bottom) hide)
      )
      (property "License" "Apache-2.0" (at 13.97 -17.78 0)
        (effects (font (size 1.27 1.27) (thickness 0.15)) (justify left bottom) hide)
      )
      (property "ki_keywords" "FUSE, PASSIVE" (at 0 0 0)
        (effects (font (size 1.27 1.27)) hide)
      )
      (property "ki_description" "Resettable Fuse, PPTC, 1206 (3216 Metric), PolySwitch Low Rho Series, 6 VDC, 4.5 A, 9 A, 2 s" (at 0 0 0)
        (effects (font (size 1.27 1.27)) hide)
      )
      (symbol "PTC_4.5A_1206_0_1"
        (polyline
          (pts
            (xy 1.27 0)
            (xy 3.81 0)
          )
          (stroke (width 0) (type default))
          (fill (type none))
        )
        (rectangle (start 1.27 0.508) (end 3.81 -0.508)
          (stroke (width 0) (type default))
          (fill (type none))
        )
      )
      (symbol "PTC_4.5A_1206_1_1"
        (pin passive line (at 0 0 0) (length 1.27)
          (name "~" (effects (font (size 1.27 1.27))))
          (number "1" (effects (font (size 1.27 1.27))))
        )
        (pin passive line (at 5.08 0 180) (length 1.27)
          (name "~" (effects (font (size 1.27 1.27))))
          (number "2" (effects (font (size 1.27 1.27))))
        )
      )
    )
	(symbol "scalenode-cm4-baseboard:PWR_FLAG" (power) (pin_numbers hide) (pin_names (offset 0) hide) (in_bom yes) (on_board yes)
      (property "Reference" "#FLG" (at 0 1.905 0)
        (effects (font (size 1.27 1.27)) hide)
      )
      (property "Value" "PWR_FLAG" (at 0 3.81 0)
        (effects (font (size 1.27 1.27)))
      )
      (property "Footprint" "" (at 0 0 0)
        (effects (font (size 1.27 1.27)) hide)
      )
      (property "Datasheet" "" (at 0 0 0)
        (effects (font (size 1.27 1.27)) hide)
      )
      (symbol "PWR_FLAG_0_0"
        (pin power_out line (at 0 0 90) (length 0)
          (name "pwr" (effects (font (size 1.27 1.27))))
          (number "1" (effects (font (size 1.27 1.27))))
        )
      )
      (symbol "PWR_FLAG_0_1"
        (polyline
          (pts
            (xy 0 0)
            (xy 0 1.27)
            (xy -1.016 1.905)
            (xy 0 2.54)
            (xy 1.016 1.905)
            (xy 0 1.27)
          )
          (stroke (width 0) (type default))
          (fill (type none))
        )
      )
    )
	(symbol "scalenode-cm4-baseboard:R_0R_1206" (pin_numbers hide) (pin_names hide) (in_bom yes) (on_board yes)
      (property "Reference" "R" (at 20.32 -5.08 0)
        (effects (font (size 1.27 1.27) (thickness 0.15)) (justify left bottom))
      )
      (property "Value" "R_0R_1206" (at 20.32 -12.7 0)
        (effects (font (size 1.27 1.27) (thickness 0.15)) (justify left bottom) hide)
      )
      (property "Footprint" "scalenode-cm4-baseboard-footprints:R_1206_3216Metric" (at 20.32 -15.24 0)
        (effects (font (size 1.27 1.27) (thickness 0.15)) (justify left bottom) hide)
      )
      (property "Datasheet" "https://www.farnell.com/datasheets/2860635.pdf" (at 20.32 -17.78 0)
        (effects (font (size 1.27 1.27) (thickness 0.15)) (justify left bottom) hide)
      )
      (property "MPN" "MCMR12X000_PTL" (at 20.32 -20.32 0)
        (effects (font (size 1.27 1.27) (thickness 0.15)) (justify left bottom) hide)
      )
      (property "Manufacturer" "Multicomp Pro" (at 20.32 -22.86 0)
        (effects (font (size 1.27 1.27) (thickness 0.15)) (justify left bottom) hide)
      )
      (property "License" "Apache-2.0" (at 20.32 -25.4 0)
        (effects (font (size 1.27 1.27) (thickness 0.15)) (justify left bottom) hide)
      )
      (property "Author" "Antmicro" (at 20.32 -27.94 0)
        (effects (font (size 1.27 1.27) (thickness 0.15)) (justify left bottom) hide)
      )
      (property "Val" "0R" (at 20.32 -7.62 0)
        (effects (font (size 1.27 1.27) (thickness 0.15)) (justify left bottom))
      )
      (property "Tolerance" "~" (at 20.32 -10.16 0)
        (effects (font (size 1.27 1.27)) (justify left bottom) hide)
      )
      (property "Current" "2A" (at 20.32 -30.48 0)
        (effects (font (size 1.27 1.27) (thickness 0.15)) (justify left bottom))
      )
      (property "ki_description" "Zero Ohm Resistor, Jumper, 1206 [3216 Metric], Thick Film, 250 mW, 2 A, Surface Mount Device" (at 0 0 0)
        (effects (font (size 1.27 1.27)) hide)
      )
      (symbol "R_0R_1206_0_1"
        (rectangle (start 0.635 0.889) (end 4.445 -0.889)
          (stroke (width 0.254) (type default))
          (fill (type none))
        )
      )
      (symbol "R_0R_1206_1_1"
        (pin passive line (at 0 0 0) (length 0.635)
          (name "~" (effects (font (size 1.27 1.27))))
          (number "1" (effects (font (size 1.27 1.27))))
        )
        (pin passive line (at 5.08 0 180) (length 0.635)
          (name "~" (effects (font (size 1.27 1.27))))
          (number "2" (effects (font (size 1.27 1.27))))
        )
      )
    )
	(symbol "scalenode-cm4-baseboard:R_10k_0402" (pin_numbers hide) (pin_names hide) (in_bom yes) (on_board yes)
      (property "Reference" "R" (at 20.32 -5.08 0)
        (effects (font (size 1.27 1.27) (thickness 0.15)) (justify left bottom))
      )
      (property "Value" "R_10k_0402" (at 20.32 -12.7 0)
        (effects (font (size 1.27 1.27) (thickness 0.15)) (justify left bottom) hide)
      )
      (property "Footprint" "scalenode-cm4-baseboard-footprints:R_0402_1005Metric" (at 20.32 -15.24 0)
        (effects (font (size 1.27 1.27) (thickness 0.15)) (justify left bottom) hide)
      )
      (property "Datasheet" "https://www.bourns.com/docs/product-datasheets/cr.pdf" (at 20.32 -17.78 0)
        (effects (font (size 1.27 1.27) (thickness 0.15)) (justify left bottom) hide)
      )
      (property "MPN" "CR0402-FX-1002GLF" (at 20.32 -20.32 0)
        (effects (font (size 1.27 1.27) (thickness 0.15)) (justify left bottom) hide)
      )
      (property "Manufacturer" "Bourns" (at 20.32 -22.86 0)
        (effects (font (size 1.27 1.27) (thickness 0.15)) (justify left bottom) hide)
      )
      (property "License" "Apache-2.0" (at 20.32 -25.4 0)
        (effects (font (size 1.27 1.27) (thickness 0.15)) (justify left bottom) hide)
      )
      (property "Author" "Antmicro" (at 20.32 -27.94 0)
        (effects (font (size 1.27 1.27) (thickness 0.15)) (justify left bottom) hide)
      )
      (property "Val" "10k" (at 20.32 -7.62 0)
        (effects (font (size 1.27 1.27) (thickness 0.15)) (justify left bottom))
      )
      (property "Tolerance" "1%" (at 20.32 -10.16 0)
        (effects (font (size 1.27 1.27)) (justify left bottom) hide)
      )
      (property "ki_description" "SMD Chip Resistor, 10 kohm, ± 1%, 62.5 mW, 0402 [1005 Metric], Thick Film, General Purpose" (at 0 0 0)
        (effects (font (size 1.27 1.27)) hide)
      )
      (symbol "R_10k_0402_0_1"
        (rectangle (start 0.635 0.889) (end 4.445 -0.889)
          (stroke (width 0.254) (type default))
          (fill (type none))
        )
      )
      (symbol "R_10k_0402_1_1"
        (pin passive line (at 0 0 0) (length 0.635)
          (name "~" (effects (font (size 1.27 1.27))))
          (number "1" (effects (font (size 1.27 1.27))))
        )
        (pin passive line (at 5.08 0 180) (length 0.635)
          (name "~" (effects (font (size 1.27 1.27))))
          (number "2" (effects (font (size 1.27 1.27))))
        )
      )
    )
	(symbol "scalenode-cm4-baseboard:R_10k_0603" (pin_numbers hide) (pin_names hide) (in_bom yes) (on_board yes)
      (property "Reference" "R" (at 20.32 -5.08 0)
        (effects (font (size 1.27 1.27) (thickness 0.15)) (justify left bottom))
      )
      (property "Value" "R_10k_0603" (at 20.32 -12.7 0)
        (effects (font (size 1.27 1.27) (thickness 0.15)) (justify left bottom) hide)
      )
      (property "Footprint" "scalenode-cm4-baseboard-footprints:R_0603_1608Metric" (at 20.32 -15.24 0)
        (effects (font (size 1.27 1.27) (thickness 0.15)) (justify left bottom) hide)
      )
      (property "Datasheet" "https://www.bourns.com/docs/product-datasheets/cr.pdf" (at 20.32 -17.78 0)
        (effects (font (size 1.27 1.27) (thickness 0.15)) (justify left bottom) hide)
      )
      (property "MPN" "CR0603-FX-1002ELF" (at 20.32 -20.32 0)
        (effects (font (size 1.27 1.27) (thickness 0.15)) (justify left bottom) hide)
      )
      (property "Manufacturer" "Bourns" (at 20.32 -22.86 0)
        (effects (font (size 1.27 1.27) (thickness 0.15)) (justify left bottom) hide)
      )
      (property "License" "Apache-2.0" (at 20.32 -25.4 0)
        (effects (font (size 1.27 1.27) (thickness 0.15)) (justify left bottom) hide)
      )
      (property "Author" "Antmicro" (at 20.32 -27.94 0)
        (effects (font (size 1.27 1.27) (thickness 0.15)) (justify left bottom) hide)
      )
      (property "Val" "10k" (at 20.32 -7.62 0)
        (effects (font (size 1.27 1.27) (thickness 0.15)) (justify left bottom))
      )
      (property "Tolerance" "1%" (at 20.32 -10.16 0)
        (effects (font (size 1.27 1.27)) (justify left bottom) hide)
      )
      (property "ki_description" "SMD Chip Resistor, 10 kohm, ± 1%, 100 mW, 0603 [1608 Metric], Thick Film, General Purpose" (at 0 0 0)
        (effects (font (size 1.27 1.27)) hide)
      )
      (symbol "R_10k_0603_0_1"
        (rectangle (start 0.635 0.889) (end 4.445 -0.889)
          (stroke (width 0.254) (type default))
          (fill (type none))
        )
      )
      (symbol "R_10k_0603_1_1"
        (pin passive line (at 0 0 0) (length 0.635)
          (name "~" (effects (font (size 1.27 1.27))))
          (number "1" (effects (font (size 1.27 1.27))))
        )
        (pin passive line (at 5.08 0 180) (length 0.635)
          (name "~" (effects (font (size 1.27 1.27))))
          (number "2" (effects (font (size 1.27 1.27))))
        )
      )
    )
	(symbol "scalenode-cm4-baseboard:R_15k_0603" (pin_numbers hide) (pin_names hide) (in_bom yes) (on_board yes)
      (property "Reference" "R" (at 20.32 -5.08 0)
        (effects (font (size 1.27 1.27) (thickness 0.15)) (justify left bottom))
      )
      (property "Value" "R_15k_0603" (at 20.32 -12.7 0)
        (effects (font (size 1.27 1.27) (thickness 0.15)) (justify left bottom) hide)
      )
      (property "Footprint" "scalenode-cm4-baseboard-footprints:R_0603_1608Metric" (at 20.32 -15.24 0)
        (effects (font (size 1.27 1.27) (thickness 0.15)) (justify left bottom) hide)
      )
      (property "Datasheet" "https://www.bourns.com/docs/product-datasheets/cr.pdf" (at 20.32 -17.78 0)
        (effects (font (size 1.27 1.27) (thickness 0.15)) (justify left bottom) hide)
      )
      (property "MPN" "CR0603-FX-1502ELF" (at 20.32 -20.32 0)
        (effects (font (size 1.27 1.27) (thickness 0.15)) (justify left bottom) hide)
      )
      (property "Manufacturer" "Bourns" (at 20.32 -22.86 0)
        (effects (font (size 1.27 1.27) (thickness 0.15)) (justify left bottom) hide)
      )
      (property "License" "Apache-2.0" (at 20.32 -25.4 0)
        (effects (font (size 1.27 1.27) (thickness 0.15)) (justify left bottom) hide)
      )
      (property "Author" "Antmicro" (at 20.32 -27.94 0)
        (effects (font (size 1.27 1.27) (thickness 0.15)) (justify left bottom) hide)
      )
      (property "Val" "15k" (at 20.32 -7.62 0)
        (effects (font (size 1.27 1.27) (thickness 0.15)) (justify left bottom))
      )
      (property "Tolerance" "1%" (at 20.32 -10.16 0)
        (effects (font (size 1.27 1.27)) (justify left bottom) hide)
      )
      (property "ki_description" "SMD Chip Resistor, 15 kohm, ± 1%, 100 mW, 0603 [1608 Metric], Thick Film, General Purpose" (at 0 0 0)
        (effects (font (size 1.27 1.27)) hide)
      )
      (symbol "R_15k_0603_0_1"
        (rectangle (start 0.635 0.889) (end 4.445 -0.889)
          (stroke (width 0.254) (type default))
          (fill (type none))
        )
      )
      (symbol "R_15k_0603_1_1"
        (pin passive line (at 0 0 0) (length 0.635)
          (name "~" (effects (font (size 1.27 1.27))))
          (number "1" (effects (font (size 1.27 1.27))))
        )
        (pin passive line (at 5.08 0 180) (length 0.635)
          (name "~" (effects (font (size 1.27 1.27))))
          (number "2" (effects (font (size 1.27 1.27))))
        )
      )
    )
	(symbol "scalenode-cm4-baseboard:R_1k1_0402" (pin_numbers hide) (pin_names hide) (in_bom yes) (on_board yes)
      (property "Reference" "R" (at 20.32 -5.08 0)
        (effects (font (size 1.27 1.27) (thickness 0.15)) (justify left bottom))
      )
      (property "Value" "R_1k1_0402" (at 20.32 -12.7 0)
        (effects (font (size 1.27 1.27) (thickness 0.15)) (justify left bottom) hide)
      )
      (property "Footprint" "scalenode-cm4-baseboard-footprints:R_0402_1005Metric" (at 20.32 -15.24 0)
        (effects (font (size 1.27 1.27) (thickness 0.15)) (justify left bottom) hide)
      )
      (property "Datasheet" "https://www.bourns.com/docs/product-datasheets/cr.pdf" (at 20.32 -17.78 0)
        (effects (font (size 1.27 1.27) (thickness 0.15)) (justify left bottom) hide)
      )
      (property "MPN" "CR0402-FX-1101GLF" (at 20.32 -20.32 0)
        (effects (font (size 1.27 1.27) (thickness 0.15)) (justify left bottom) hide)
      )
      (property "Manufacturer" "Bourns" (at 20.32 -22.86 0)
        (effects (font (size 1.27 1.27) (thickness 0.15)) (justify left bottom) hide)
      )
      (property "License" "Apache-2.0" (at 20.32 -25.4 0)
        (effects (font (size 1.27 1.27) (thickness 0.15)) (justify left bottom) hide)
      )
      (property "Author" "Antmicro" (at 20.32 -27.94 0)
        (effects (font (size 1.27 1.27) (thickness 0.15)) (justify left bottom) hide)
      )
      (property "Val" "1k1" (at 20.32 -7.62 0)
        (effects (font (size 1.27 1.27) (thickness 0.15)) (justify left bottom))
      )
      (property "Tolerance" "1%" (at 20.32 -10.16 0)
        (effects (font (size 1.27 1.27)) (justify left bottom) hide)
      )
      (property "ki_description" "SMD Chip Resistor" (at 0 0 0)
        (effects (font (size 1.27 1.27)) hide)
      )
      (symbol "R_1k1_0402_0_1"
        (rectangle (start 0.635 0.889) (end 4.445 -0.889)
          (stroke (width 0.254) (type default))
          (fill (type none))
        )
      )
      (symbol "R_1k1_0402_1_1"
        (pin passive line (at 0 0 0) (length 0.635)
          (name "~" (effects (font (size 1.27 1.27))))
          (number "1" (effects (font (size 1.27 1.27))))
        )
        (pin passive line (at 5.08 0 180) (length 0.635)
          (name "~" (effects (font (size 1.27 1.27))))
          (number "2" (effects (font (size 1.27 1.27))))
        )
      )
    )
	(symbol "scalenode-cm4-baseboard:R_1k3_0402" (pin_numbers hide) (pin_names hide) (in_bom yes) (on_board yes)
      (property "Reference" "R" (at 20.32 -5.08 0)
        (effects (font (size 1.27 1.27) (thickness 0.15)) (justify left bottom))
      )
      (property "Value" "R_1k3_0402" (at 20.32 -12.7 0)
        (effects (font (size 1.27 1.27) (thickness 0.15)) (justify left bottom) hide)
      )
      (property "Footprint" "scalenode-cm4-baseboard-footprints:R_0402_1005Metric" (at 20.32 -15.24 0)
        (effects (font (size 1.27 1.27) (thickness 0.15)) (justify left bottom) hide)
      )
      (property "Datasheet" "https://www.bourns.com/docs/product-datasheets/cr.pdf" (at 20.32 -17.78 0)
        (effects (font (size 1.27 1.27) (thickness 0.15)) (justify left bottom) hide)
      )
      (property "MPN" "CR0402-FX-1301GLF" (at 20.32 -20.32 0)
        (effects (font (size 1.27 1.27) (thickness 0.15)) (justify left bottom) hide)
      )
      (property "Manufacturer" "Bourns" (at 20.32 -22.86 0)
        (effects (font (size 1.27 1.27) (thickness 0.15)) (justify left bottom) hide)
      )
      (property "License" "Apache-2.0" (at 20.32 -25.4 0)
        (effects (font (size 1.27 1.27) (thickness 0.15)) (justify left bottom) hide)
      )
      (property "Author" "Antmicro" (at 20.32 -27.94 0)
        (effects (font (size 1.27 1.27) (thickness 0.15)) (justify left bottom) hide)
      )
      (property "Val" "1k3" (at 20.32 -7.62 0)
        (effects (font (size 1.27 1.27) (thickness 0.15)) (justify left bottom))
      )
      (property "Tolerance" "1%" (at 20.32 -10.16 0)
        (effects (font (size 1.27 1.27)) (justify left bottom) hide)
      )
      (property "ki_description" "SMD Chip Resistor, 1.3 kohm, ± 1%, 62.5 mW, 0402 [1005 Metric], Thick Film, General Purpose" (at 0 0 0)
        (effects (font (size 1.27 1.27)) hide)
      )
      (symbol "R_1k3_0402_0_1"
        (rectangle (start 0.635 0.889) (end 4.445 -0.889)
          (stroke (width 0.254) (type default))
          (fill (type none))
        )
      )
      (symbol "R_1k3_0402_1_1"
        (pin passive line (at 0 0 0) (length 0.635)
          (name "~" (effects (font (size 1.27 1.27))))
          (number "1" (effects (font (size 1.27 1.27))))
        )
        (pin passive line (at 5.08 0 180) (length 0.635)
          (name "~" (effects (font (size 1.27 1.27))))
          (number "2" (effects (font (size 1.27 1.27))))
        )
      )
    )
	(symbol "scalenode-cm4-baseboard:R_1k_0603" (pin_numbers hide) (pin_names hide) (in_bom yes) (on_board yes)
      (property "Reference" "R" (at 20.32 -5.08 0)
        (effects (font (size 1.27 1.27) (thickness 0.15)) (justify left bottom))
      )
      (property "Value" "R_1k_0603" (at 20.32 -12.7 0)
        (effects (font (size 1.27 1.27) (thickness 0.15)) (justify left bottom) hide)
      )
      (property "Footprint" "scalenode-cm4-baseboard-footprints:R_0603_1608Metric" (at 20.32 -15.24 0)
        (effects (font (size 1.27 1.27) (thickness 0.15)) (justify left bottom) hide)
      )
      (property "Datasheet" "https://www.bourns.com/docs/product-datasheets/cr.pdf" (at 20.32 -17.78 0)
        (effects (font (size 1.27 1.27) (thickness 0.15)) (justify left bottom) hide)
      )
      (property "MPN" "CR0603-FX-1001ELF" (at 20.32 -20.32 0)
        (effects (font (size 1.27 1.27) (thickness 0.15)) (justify left bottom) hide)
      )
      (property "Manufacturer" "Bourns" (at 20.32 -22.86 0)
        (effects (font (size 1.27 1.27) (thickness 0.15)) (justify left bottom) hide)
      )
      (property "License" "Apache-2.0" (at 20.32 -25.4 0)
        (effects (font (size 1.27 1.27) (thickness 0.15)) (justify left bottom) hide)
      )
      (property "Author" "Antmicro" (at 20.32 -27.94 0)
        (effects (font (size 1.27 1.27) (thickness 0.15)) (justify left bottom) hide)
      )
      (property "Val" "1k" (at 20.32 -7.62 0)
        (effects (font (size 1.27 1.27) (thickness 0.15)) (justify left bottom))
      )
      (property "Tolerance" "1%" (at 20.32 -10.16 0)
        (effects (font (size 1.27 1.27)) (justify left bottom) hide)
      )
      (property "ki_description" "SMD Chip Resistor, 1 kohm, ± 1%, 100 mW, 0603 [1608 Metric], Thick Film, General Purpose" (at 0 0 0)
        (effects (font (size 1.27 1.27)) hide)
      )
      (symbol "R_1k_0603_0_1"
        (rectangle (start 0.635 0.889) (end 4.445 -0.889)
          (stroke (width 0.254) (type default))
          (fill (type none))
        )
      )
      (symbol "R_1k_0603_1_1"
        (pin passive line (at 0 0 0) (length 0.635)
          (name "~" (effects (font (size 1.27 1.27))))
          (number "1" (effects (font (size 1.27 1.27))))
        )
        (pin passive line (at 5.08 0 180) (length 0.635)
          (name "~" (effects (font (size 1.27 1.27))))
          (number "2" (effects (font (size 1.27 1.27))))
        )
      )
    )
	(symbol "scalenode-cm4-baseboard:R_220R_0402" (pin_numbers hide) (pin_names hide) (in_bom yes) (on_board yes)
      (property "Reference" "R" (at 20.32 -5.08 0)
        (effects (font (size 1.27 1.27) (thickness 0.15)) (justify left bottom))
      )
      (property "Value" "R_220R_0402" (at 20.32 -12.7 0)
        (effects (font (size 1.27 1.27) (thickness 0.15)) (justify left bottom) hide)
      )
      (property "Footprint" "scalenode-cm4-baseboard-footprints:R_0402_1005Metric" (at 20.32 -15.24 0)
        (effects (font (size 1.27 1.27) (thickness 0.15)) (justify left bottom) hide)
      )
      (property "Datasheet" "https://www.bourns.com/docs/product-datasheets/cr.pdf" (at 20.32 -17.78 0)
        (effects (font (size 1.27 1.27) (thickness 0.15)) (justify left bottom) hide)
      )
      (property "MPN" "CR0402-FX-2200GLF" (at 20.32 -20.32 0)
        (effects (font (size 1.27 1.27) (thickness 0.15)) (justify left bottom) hide)
      )
      (property "Manufacturer" "Bourns" (at 20.32 -22.86 0)
        (effects (font (size 1.27 1.27) (thickness 0.15)) (justify left bottom) hide)
      )
      (property "License" "Apache-2.0" (at 20.32 -25.4 0)
        (effects (font (size 1.27 1.27) (thickness 0.15)) (justify left bottom) hide)
      )
      (property "Author" "Antmicro" (at 20.32 -27.94 0)
        (effects (font (size 1.27 1.27) (thickness 0.15)) (justify left bottom) hide)
      )
      (property "Val" "220R" (at 20.32 -7.62 0)
        (effects (font (size 1.27 1.27) (thickness 0.15)) (justify left bottom))
      )
      (property "Tolerance" "1%" (at 20.32 -10.16 0)
        (effects (font (size 1.27 1.27)) (justify left bottom) hide)
      )
      (property "ki_description" "SMD Chip Resistor, 220 ohm, ± 1%, 62.5 mW, 0402 [1005 Metric], Thick Film, General Purpose" (at 0 0 0)
        (effects (font (size 1.27 1.27)) hide)
      )
      (symbol "R_220R_0402_0_1"
        (rectangle (start 0.635 0.889) (end 4.445 -0.889)
          (stroke (width 0.254) (type default))
          (fill (type none))
        )
      )
      (symbol "R_220R_0402_1_1"
        (pin passive line (at 0 0 0) (length 0.635)
          (name "~" (effects (font (size 1.27 1.27))))
          (number "1" (effects (font (size 1.27 1.27))))
        )
        (pin passive line (at 5.08 0 180) (length 0.635)
          (name "~" (effects (font (size 1.27 1.27))))
          (number "2" (effects (font (size 1.27 1.27))))
        )
      )
    )
	(symbol "scalenode-cm4-baseboard:R_22R_0402" (pin_numbers hide) (pin_names hide) (in_bom yes) (on_board yes)
      (property "Reference" "R" (at 20.32 -5.08 0)
        (effects (font (size 1.27 1.27) (thickness 0.15)) (justify left bottom))
      )
      (property "Value" "R_22R_0402" (at 20.32 -12.7 0)
        (effects (font (size 1.27 1.27) (thickness 0.15)) (justify left bottom) hide)
      )
      (property "Footprint" "scalenode-cm4-baseboard-footprints:R_0402_1005Metric" (at 20.32 -15.24 0)
        (effects (font (size 1.27 1.27) (thickness 0.15)) (justify left bottom) hide)
      )
      (property "Datasheet" "https://www.bourns.com/docs/product-datasheets/cr.pdf" (at 20.32 -17.78 0)
        (effects (font (size 1.27 1.27) (thickness 0.15)) (justify left bottom) hide)
      )
      (property "MPN" "CR0402-FX-22R0GLF" (at 20.32 -20.32 0)
        (effects (font (size 1.27 1.27) (thickness 0.15)) (justify left bottom) hide)
      )
      (property "Manufacturer" "Bourns" (at 20.32 -22.86 0)
        (effects (font (size 1.27 1.27) (thickness 0.15)) (justify left bottom) hide)
      )
      (property "License" "Apache-2.0" (at 20.32 -25.4 0)
        (effects (font (size 1.27 1.27) (thickness 0.15)) (justify left bottom) hide)
      )
      (property "Author" "Antmicro" (at 20.32 -27.94 0)
        (effects (font (size 1.27 1.27) (thickness 0.15)) (justify left bottom) hide)
      )
      (property "Val" "22R" (at 20.32 -7.62 0)
        (effects (font (size 1.27 1.27) (thickness 0.15)) (justify left bottom))
      )
      (property "Tolerance" "1%" (at 20.32 -10.16 0)
        (effects (font (size 1.27 1.27)) (justify left bottom) hide)
      )
      (property "ki_description" "SMD Chip Resistor, 22 ohm, ± 1%, 62.5 mW, 0402 [1005 Metric], Thick Film, General Purpose" (at 0 0 0)
        (effects (font (size 1.27 1.27)) hide)
      )
      (symbol "R_22R_0402_0_1"
        (rectangle (start 0.635 0.889) (end 4.445 -0.889)
          (stroke (width 0.254) (type default))
          (fill (type none))
        )
      )
      (symbol "R_22R_0402_1_1"
        (pin passive line (at 0 0 0) (length 0.635)
          (name "~" (effects (font (size 1.27 1.27))))
          (number "1" (effects (font (size 1.27 1.27))))
        )
        (pin passive line (at 5.08 0 180) (length 0.635)
          (name "~" (effects (font (size 1.27 1.27))))
          (number "2" (effects (font (size 1.27 1.27))))
        )
      )
    )
	(symbol "scalenode-cm4-baseboard:R_24k9_0402" (pin_numbers hide) (pin_names hide) (in_bom yes) (on_board yes)
      (property "Reference" "R" (at 20.32 -5.08 0)
        (effects (font (size 1.27 1.27) (thickness 0.15)) (justify left bottom))
      )
      (property "Value" "R_24k9_0402" (at 20.32 -12.7 0)
        (effects (font (size 1.27 1.27) (thickness 0.15)) (justify left bottom) hide)
      )
      (property "Footprint" "scalenode-cm4-baseboard-footprints:R_0402_1005Metric" (at 20.32 -15.24 0)
        (effects (font (size 1.27 1.27) (thickness 0.15)) (justify left bottom) hide)
      )
      (property "Datasheet" "https://www.bourns.com/docs/product-datasheets/cr.pdf" (at 20.32 -17.78 0)
        (effects (font (size 1.27 1.27) (thickness 0.15)) (justify left bottom) hide)
      )
      (property "MPN" "CR0402-FX-2492GLF" (at 20.32 -20.32 0)
        (effects (font (size 1.27 1.27) (thickness 0.15)) (justify left bottom) hide)
      )
      (property "Manufacturer" "Bourns" (at 20.32 -22.86 0)
        (effects (font (size 1.27 1.27) (thickness 0.15)) (justify left bottom) hide)
      )
      (property "License" "Apache-2.0" (at 20.32 -25.4 0)
        (effects (font (size 1.27 1.27) (thickness 0.15)) (justify left bottom) hide)
      )
      (property "Author" "Antmicro" (at 20.32 -27.94 0)
        (effects (font (size 1.27 1.27) (thickness 0.15)) (justify left bottom) hide)
      )
      (property "Val" "24k9" (at 20.32 -7.62 0)
        (effects (font (size 1.27 1.27) (thickness 0.15)) (justify left bottom))
      )
      (property "Tolerance" "1%" (at 20.32 -10.16 0)
        (effects (font (size 1.27 1.27)) (justify left bottom) hide)
      )
      (property "ki_description" "SMD Chip Resistor, 24.9 kohm, ± 1%, 63 mW, 0402 [1005 Metric], Thick Film, General Purpose" (at 0 0 0)
        (effects (font (size 1.27 1.27)) hide)
      )
      (symbol "R_24k9_0402_0_1"
        (rectangle (start 0.635 0.889) (end 4.445 -0.889)
          (stroke (width 0.254) (type default))
          (fill (type none))
        )
      )
      (symbol "R_24k9_0402_1_1"
        (pin passive line (at 0 0 0) (length 0.635)
          (name "~" (effects (font (size 1.27 1.27))))
          (number "1" (effects (font (size 1.27 1.27))))
        )
        (pin passive line (at 5.08 0 180) (length 0.635)
          (name "~" (effects (font (size 1.27 1.27))))
          (number "2" (effects (font (size 1.27 1.27))))
        )
      )
    )
	(symbol "scalenode-cm4-baseboard:R_270R_0603" (pin_numbers hide) (pin_names hide) (in_bom yes) (on_board yes)
      (property "Reference" "R" (at 20.32 -5.08 0)
        (effects (font (size 1.27 1.27) (thickness 0.15)) (justify left bottom))
      )
      (property "Value" "R_270R_0603" (at 20.32 -12.7 0)
        (effects (font (size 1.27 1.27) (thickness 0.15)) (justify left bottom) hide)
      )
      (property "Footprint" "scalenode-cm4-baseboard-footprints:R_0603_1608Metric" (at 20.32 -15.24 0)
        (effects (font (size 1.27 1.27) (thickness 0.15)) (justify left bottom) hide)
      )
      (property "Datasheet" "https://www.bourns.com/docs/product-datasheets/cr.pdf" (at 20.32 -17.78 0)
        (effects (font (size 1.27 1.27) (thickness 0.15)) (justify left bottom) hide)
      )
      (property "MPN" "CR0603-FX-2700ELF" (at 20.32 -20.32 0)
        (effects (font (size 1.27 1.27) (thickness 0.15)) (justify left bottom) hide)
      )
      (property "Manufacturer" "Bourns" (at 20.32 -22.86 0)
        (effects (font (size 1.27 1.27) (thickness 0.15)) (justify left bottom) hide)
      )
      (property "License" "Apache-2.0" (at 20.32 -25.4 0)
        (effects (font (size 1.27 1.27) (thickness 0.15)) (justify left bottom) hide)
      )
      (property "Author" "Antmicro" (at 20.32 -27.94 0)
        (effects (font (size 1.27 1.27) (thickness 0.15)) (justify left bottom) hide)
      )
      (property "Val" "270R" (at 20.32 -7.62 0)
        (effects (font (size 1.27 1.27) (thickness 0.15)) (justify left bottom))
      )
      (property "Tolerance" "1%" (at 20.32 -10.16 0)
        (effects (font (size 1.27 1.27)) (justify left bottom) hide)
      )
      (property "ki_description" "SMD Chip Resistor, 270 ohm, ± 1%, 100 mW, 0603 [1608 Metric], Thick Film, General Purpose" (at 0 0 0)
        (effects (font (size 1.27 1.27)) hide)
      )
      (symbol "R_270R_0603_0_1"
        (rectangle (start 0.635 0.889) (end 4.445 -0.889)
          (stroke (width 0.254) (type default))
          (fill (type none))
        )
      )
      (symbol "R_270R_0603_1_1"
        (pin passive line (at 0 0 0) (length 0.635)
          (name "~" (effects (font (size 1.27 1.27))))
          (number "1" (effects (font (size 1.27 1.27))))
        )
        (pin passive line (at 5.08 0 180) (length 0.635)
          (name "~" (effects (font (size 1.27 1.27))))
          (number "2" (effects (font (size 1.27 1.27))))
        )
      )
    )
	(symbol "scalenode-cm4-baseboard:R_2k2_0402" (pin_numbers hide) (pin_names hide) (in_bom yes) (on_board yes)
      (property "Reference" "R" (at 20.32 -5.08 0)
        (effects (font (size 1.27 1.27) (thickness 0.15)) (justify left bottom))
      )
      (property "Value" "R_2k2_0402" (at 20.32 -12.7 0)
        (effects (font (size 1.27 1.27) (thickness 0.15)) (justify left bottom) hide)
      )
      (property "Footprint" "scalenode-cm4-baseboard-footprints:R_0402_1005Metric" (at 20.32 -15.24 0)
        (effects (font (size 1.27 1.27) (thickness 0.15)) (justify left bottom) hide)
      )
      (property "Datasheet" "https://www.bourns.com/docs/product-datasheets/cr.pdf" (at 20.32 -17.78 0)
        (effects (font (size 1.27 1.27) (thickness 0.15)) (justify left bottom) hide)
      )
      (property "MPN" "CR0402-FX-2201GLF" (at 20.32 -20.32 0)
        (effects (font (size 1.27 1.27) (thickness 0.15)) (justify left bottom) hide)
      )
      (property "Manufacturer" "Bourns" (at 20.32 -22.86 0)
        (effects (font (size 1.27 1.27) (thickness 0.15)) (justify left bottom) hide)
      )
      (property "License" "Apache-2.0" (at 20.32 -25.4 0)
        (effects (font (size 1.27 1.27) (thickness 0.15)) (justify left bottom) hide)
      )
      (property "Author" "Antmicro" (at 20.32 -27.94 0)
        (effects (font (size 1.27 1.27) (thickness 0.15)) (justify left bottom) hide)
      )
      (property "Val" "2k2" (at 20.32 -7.62 0)
        (effects (font (size 1.27 1.27) (thickness 0.15)) (justify left bottom))
      )
      (property "Tolerance" "1%" (at 20.32 -10.16 0)
        (effects (font (size 1.27 1.27)) (justify left bottom) hide)
      )
      (property "ki_description" "SMD Chip Resistor, 2.2 kohm, ± 1%, 62.5 mW, 0402 [1005 Metric], Thick Film, General Purpose" (at 0 0 0)
        (effects (font (size 1.27 1.27)) hide)
      )
      (symbol "R_2k2_0402_0_1"
        (rectangle (start 0.635 0.889) (end 4.445 -0.889)
          (stroke (width 0.254) (type default))
          (fill (type none))
        )
      )
      (symbol "R_2k2_0402_1_1"
        (pin passive line (at 0 0 0) (length 0.635)
          (name "~" (effects (font (size 1.27 1.27))))
          (number "1" (effects (font (size 1.27 1.27))))
        )
        (pin passive line (at 5.08 0 180) (length 0.635)
          (name "~" (effects (font (size 1.27 1.27))))
          (number "2" (effects (font (size 1.27 1.27))))
        )
      )
    )
	(symbol "scalenode-cm4-baseboard:R_32k4_0805" (pin_numbers hide) (pin_names hide) (in_bom yes) (on_board yes)
      (property "Reference" "R" (at 20.32 -5.08 0)
        (effects (font (size 1.27 1.27) (thickness 0.15)) (justify left bottom))
      )
      (property "Value" "R_32k4_0805" (at 20.32 -12.7 0)
        (effects (font (size 1.27 1.27) (thickness 0.15)) (justify left bottom) hide)
      )
      (property "Footprint" "scalenode-cm4-baseboard-footprints:R_0805_2012Metric" (at 20.32 -15.24 0)
        (effects (font (size 1.27 1.27) (thickness 0.15)) (justify left bottom) hide)
      )
      (property "Datasheet" "https://www.bourns.com/docs/product-datasheets/cr.pdf" (at 20.32 -17.78 0)
        (effects (font (size 1.27 1.27) (thickness 0.15)) (justify left bottom) hide)
      )
      (property "MPN" "CR0805-FX-3242ELF" (at 20.32 -20.32 0)
        (effects (font (size 1.27 1.27) (thickness 0.15)) (justify left bottom) hide)
      )
      (property "Manufacturer" "Bourns" (at 20.32 -22.86 0)
        (effects (font (size 1.27 1.27) (thickness 0.15)) (justify left bottom) hide)
      )
      (property "License" "Apache-2.0" (at 20.32 -25.4 0)
        (effects (font (size 1.27 1.27) (thickness 0.15)) (justify left bottom) hide)
      )
      (property "Author" "Antmicro" (at 20.32 -27.94 0)
        (effects (font (size 1.27 1.27) (thickness 0.15)) (justify left bottom) hide)
      )
      (property "Val" "32k4" (at 20.32 -7.62 0)
        (effects (font (size 1.27 1.27) (thickness 0.15)) (justify left bottom))
      )
      (property "Tolerance" "1%" (at 20.32 -10.16 0)
        (effects (font (size 1.27 1.27)) (justify left bottom) hide)
      )
      (property "ki_description" "SMD Chip Resistor" (at 0 0 0)
        (effects (font (size 1.27 1.27)) hide)
      )
      (symbol "R_32k4_0805_0_1"
        (rectangle (start 0.635 0.889) (end 4.445 -0.889)
          (stroke (width 0.254) (type default))
          (fill (type none))
        )
      )
      (symbol "R_32k4_0805_1_1"
        (pin passive line (at 0 0 0) (length 0.635)
          (name "~" (effects (font (size 1.27 1.27))))
          (number "1" (effects (font (size 1.27 1.27))))
        )
        (pin passive line (at 5.08 0 180) (length 0.635)
          (name "~" (effects (font (size 1.27 1.27))))
          (number "2" (effects (font (size 1.27 1.27))))
        )
      )
    )
	(symbol "scalenode-cm4-baseboard:R_330R_0402" (pin_numbers hide) (pin_names hide) (in_bom yes) (on_board yes)
      (property "Reference" "R" (at 20.32 -5.08 0)
        (effects (font (size 1.27 1.27) (thickness 0.15)) (justify left bottom))
      )
      (property "Value" "R_330R_0402" (at 20.32 -12.7 0)
        (effects (font (size 1.27 1.27) (thickness 0.15)) (justify left bottom) hide)
      )
      (property "Footprint" "scalenode-cm4-baseboard-footprints:R_0402_1005Metric" (at 20.32 -15.24 0)
        (effects (font (size 1.27 1.27) (thickness 0.15)) (justify left bottom) hide)
      )
      (property "Datasheet" "https://www.bourns.com/docs/product-datasheets/cr.pdf" (at 20.32 -17.78 0)
        (effects (font (size 1.27 1.27) (thickness 0.15)) (justify left bottom) hide)
      )
      (property "MPN" "CR0402-FX-3300GLF" (at 20.32 -20.32 0)
        (effects (font (size 1.27 1.27) (thickness 0.15)) (justify left bottom) hide)
      )
      (property "Manufacturer" "Bourns" (at 20.32 -22.86 0)
        (effects (font (size 1.27 1.27) (thickness 0.15)) (justify left bottom) hide)
      )
      (property "License" "Apache-2.0" (at 20.32 -25.4 0)
        (effects (font (size 1.27 1.27) (thickness 0.15)) (justify left bottom) hide)
      )
      (property "Author" "Antmicro" (at 20.32 -27.94 0)
        (effects (font (size 1.27 1.27) (thickness 0.15)) (justify left bottom) hide)
      )
      (property "Val" "330R" (at 20.32 -7.62 0)
        (effects (font (size 1.27 1.27) (thickness 0.15)) (justify left bottom))
      )
      (property "Tolerance" "1%" (at 20.32 -10.16 0)
        (effects (font (size 1.27 1.27)) (justify left bottom) hide)
      )
      (property "ki_description" "SMD Chip Resistor, 330 ohm, ± 1%, 62.5 mW, 0402 [1005 Metric], Thick Film, General Purpose" (at 0 0 0)
        (effects (font (size 1.27 1.27)) hide)
      )
      (symbol "R_330R_0402_0_1"
        (rectangle (start 0.635 0.889) (end 4.445 -0.889)
          (stroke (width 0.254) (type default))
          (fill (type none))
        )
      )
      (symbol "R_330R_0402_1_1"
        (pin passive line (at 0 0 0) (length 0.635)
          (name "~" (effects (font (size 1.27 1.27))))
          (number "1" (effects (font (size 1.27 1.27))))
        )
        (pin passive line (at 5.08 0 180) (length 0.635)
          (name "~" (effects (font (size 1.27 1.27))))
          (number "2" (effects (font (size 1.27 1.27))))
        )
      )
    )
	(symbol "scalenode-cm4-baseboard:R_33k2_0402" (pin_numbers hide) (pin_names hide) (in_bom yes) (on_board yes)
      (property "Reference" "R" (at 20.32 -5.08 0)
        (effects (font (size 1.27 1.27) (thickness 0.15)) (justify left bottom))
      )
      (property "Value" "R_33k2_0402" (at 20.32 -12.7 0)
        (effects (font (size 1.27 1.27) (thickness 0.15)) (justify left bottom) hide)
      )
      (property "Footprint" "scalenode-cm4-baseboard-footprints:R_0402_1005Metric" (at 20.32 -15.24 0)
        (effects (font (size 1.27 1.27) (thickness 0.15)) (justify left bottom) hide)
      )
      (property "Datasheet" "https://www.bourns.com/docs/product-datasheets/cr.pdf" (at 20.32 -17.78 0)
        (effects (font (size 1.27 1.27) (thickness 0.15)) (justify left bottom) hide)
      )
      (property "MPN" "CR0402-FX-3322GLF" (at 20.32 -20.32 0)
        (effects (font (size 1.27 1.27) (thickness 0.15)) (justify left bottom) hide)
      )
      (property "Manufacturer" "Bourns" (at 20.32 -22.86 0)
        (effects (font (size 1.27 1.27) (thickness 0.15)) (justify left bottom) hide)
      )
      (property "License" "Apache-2.0" (at 20.32 -25.4 0)
        (effects (font (size 1.27 1.27) (thickness 0.15)) (justify left bottom) hide)
      )
      (property "Author" "Antmicro" (at 20.32 -27.94 0)
        (effects (font (size 1.27 1.27) (thickness 0.15)) (justify left bottom) hide)
      )
      (property "Val" "33k2" (at 20.32 -7.62 0)
        (effects (font (size 1.27 1.27) (thickness 0.15)) (justify left bottom))
      )
      (property "Tolerance" "1%" (at 20.32 -10.16 0)
        (effects (font (size 1.27 1.27)) (justify left bottom) hide)
      )
      (property "ki_description" "SMD Chip Resistor, 33.2 kohm, ± 1%, 63 mW, 0402 [1005 Metric], Thick Film, General Purpose" (at 0 0 0)
        (effects (font (size 1.27 1.27)) hide)
      )
      (symbol "R_33k2_0402_0_1"
        (rectangle (start 0.635 0.889) (end 4.445 -0.889)
          (stroke (width 0.254) (type default))
          (fill (type none))
        )
      )
      (symbol "R_33k2_0402_1_1"
        (pin passive line (at 0 0 0) (length 0.635)
          (name "~" (effects (font (size 1.27 1.27))))
          (number "1" (effects (font (size 1.27 1.27))))
        )
        (pin passive line (at 5.08 0 180) (length 0.635)
          (name "~" (effects (font (size 1.27 1.27))))
          (number "2" (effects (font (size 1.27 1.27))))
        )
      )
    )
	(symbol "scalenode-cm4-baseboard:R_470R_0402" (pin_numbers hide) (pin_names hide) (in_bom yes) (on_board yes)
      (property "Reference" "R" (at 20.32 -5.08 0)
        (effects (font (size 1.27 1.27) (thickness 0.15)) (justify left bottom))
      )
      (property "Value" "R_470R_0402" (at 20.32 -12.7 0)
        (effects (font (size 1.27 1.27) (thickness 0.15)) (justify left bottom) hide)
      )
      (property "Footprint" "scalenode-cm4-baseboard-footprints:R_0402_1005Metric" (at 20.32 -15.24 0)
        (effects (font (size 1.27 1.27) (thickness 0.15)) (justify left bottom) hide)
      )
      (property "Datasheet" "https://www.bourns.com/docs/product-datasheets/cr.pdf" (at 20.32 -17.78 0)
        (effects (font (size 1.27 1.27) (thickness 0.15)) (justify left bottom) hide)
      )
      (property "MPN" "CR0402-FX-4700GLF" (at 20.32 -20.32 0)
        (effects (font (size 1.27 1.27) (thickness 0.15)) (justify left bottom) hide)
      )
      (property "Manufacturer" "Bourns" (at 20.32 -22.86 0)
        (effects (font (size 1.27 1.27) (thickness 0.15)) (justify left bottom) hide)
      )
      (property "License" "Apache-2.0" (at 20.32 -25.4 0)
        (effects (font (size 1.27 1.27) (thickness 0.15)) (justify left bottom) hide)
      )
      (property "Author" "Antmicro" (at 20.32 -27.94 0)
        (effects (font (size 1.27 1.27) (thickness 0.15)) (justify left bottom) hide)
      )
      (property "Val" "470R" (at 20.32 -7.62 0)
        (effects (font (size 1.27 1.27) (thickness 0.15)) (justify left bottom))
      )
      (property "Tolerance" "1%" (at 20.32 -10.16 0)
        (effects (font (size 1.27 1.27)) (justify left bottom) hide)
      )
      (property "ki_description" "SMD Chip Resistor, 470 ohm, ± 1%, 62.5 mW, 0402 [1005 Metric], Thick Film, General Purpose" (at 0 0 0)
        (effects (font (size 1.27 1.27)) hide)
      )
      (symbol "R_470R_0402_0_1"
        (rectangle (start 0.635 0.889) (end 4.445 -0.889)
          (stroke (width 0.254) (type default))
          (fill (type none))
        )
      )
      (symbol "R_470R_0402_1_1"
        (pin passive line (at 0 0 0) (length 0.635)
          (name "~" (effects (font (size 1.27 1.27))))
          (number "1" (effects (font (size 1.27 1.27))))
        )
        (pin passive line (at 5.08 0 180) (length 0.635)
          (name "~" (effects (font (size 1.27 1.27))))
          (number "2" (effects (font (size 1.27 1.27))))
        )
      )
    )
	(symbol "scalenode-cm4-baseboard:R_49k9_0402" (pin_numbers hide) (pin_names hide) (in_bom yes) (on_board yes)
      (property "Reference" "R" (at 20.32 -5.08 0)
        (effects (font (size 1.27 1.27) (thickness 0.15)) (justify left bottom))
      )
      (property "Value" "R_49k9_0402" (at 20.32 -12.7 0)
        (effects (font (size 1.27 1.27) (thickness 0.15)) (justify left bottom) hide)
      )
      (property "Footprint" "scalenode-cm4-baseboard-footprints:R_0402_1005Metric" (at 20.32 -15.24 0)
        (effects (font (size 1.27 1.27) (thickness 0.15)) (justify left bottom) hide)
      )
      (property "Datasheet" "https://www.bourns.com/docs/product-datasheets/cr.pdf" (at 20.32 -17.78 0)
        (effects (font (size 1.27 1.27) (thickness 0.15)) (justify left bottom) hide)
      )
      (property "MPN" "CR0402-FX-4992GLF" (at 20.32 -20.32 0)
        (effects (font (size 1.27 1.27) (thickness 0.15)) (justify left bottom) hide)
      )
      (property "Manufacturer" "Bourns" (at 20.32 -22.86 0)
        (effects (font (size 1.27 1.27) (thickness 0.15)) (justify left bottom) hide)
      )
      (property "License" "Apache-2.0" (at 20.32 -25.4 0)
        (effects (font (size 1.27 1.27) (thickness 0.15)) (justify left bottom) hide)
      )
      (property "Author" "Antmicro" (at 20.32 -27.94 0)
        (effects (font (size 1.27 1.27) (thickness 0.15)) (justify left bottom) hide)
      )
      (property "Val" "49k9" (at 20.32 -7.62 0)
        (effects (font (size 1.27 1.27) (thickness 0.15)) (justify left bottom))
      )
      (property "Tolerance" "1%" (at 20.32 -10.16 0)
        (effects (font (size 1.27 1.27)) (justify left bottom) hide)
      )
      (property "ki_description" "SMD Chip Resistor, 49.9 kohm, ± 1%, 63 mW, 0402 [1005 Metric], Thick Film, General Purpose" (at 0 0 0)
        (effects (font (size 1.27 1.27)) hide)
      )
      (symbol "R_49k9_0402_0_1"
        (rectangle (start 0.635 0.889) (end 4.445 -0.889)
          (stroke (width 0.254) (type default))
          (fill (type none))
        )
      )
      (symbol "R_49k9_0402_1_1"
        (pin passive line (at 0 0 0) (length 0.635)
          (name "~" (effects (font (size 1.27 1.27))))
          (number "1" (effects (font (size 1.27 1.27))))
        )
        (pin passive line (at 5.08 0 180) (length 0.635)
          (name "~" (effects (font (size 1.27 1.27))))
          (number "2" (effects (font (size 1.27 1.27))))
        )
      )
    )
	(symbol "scalenode-cm4-baseboard:R_63R4_0402" (pin_numbers hide) (pin_names hide) (in_bom yes) (on_board yes)
      (property "Reference" "R" (at 20.32 -5.08 0)
        (effects (font (size 1.27 1.27) (thickness 0.15)) (justify left bottom))
      )
      (property "Value" "R_63R4_0402" (at 20.32 -12.7 0)
        (effects (font (size 1.27 1.27) (thickness 0.15)) (justify left bottom) hide)
      )
      (property "Footprint" "scalenode-cm4-baseboard-footprints:R_0402_1005Metric" (at 20.32 -15.24 0)
        (effects (font (size 1.27 1.27) (thickness 0.15)) (justify left bottom) hide)
      )
      (property "Datasheet" "https://www.bourns.com/docs/product-datasheets/cr.pdf" (at 20.32 -17.78 0)
        (effects (font (size 1.27 1.27) (thickness 0.15)) (justify left bottom) hide)
      )
      (property "MPN" "CR0402-FX-63R4GLF" (at 20.32 -20.32 0)
        (effects (font (size 1.27 1.27) (thickness 0.15)) (justify left bottom) hide)
      )
      (property "Manufacturer" "Bourns" (at 20.32 -22.86 0)
        (effects (font (size 1.27 1.27) (thickness 0.15)) (justify left bottom) hide)
      )
      (property "License" "Apache-2.0" (at 20.32 -25.4 0)
        (effects (font (size 1.27 1.27) (thickness 0.15)) (justify left bottom) hide)
      )
      (property "Author" "Antmicro" (at 20.32 -27.94 0)
        (effects (font (size 1.27 1.27) (thickness 0.15)) (justify left bottom) hide)
      )
      (property "Val" "63R4" (at 20.32 -7.62 0)
        (effects (font (size 1.27 1.27) (thickness 0.15)) (justify left bottom))
      )
      (property "Tolerance" "1%" (at 20.32 -10.16 0)
        (effects (font (size 1.27 1.27)) (justify left bottom) hide)
      )
      (property "ki_description" "SMD Chip Resistor, 63.4 ohm, ± 1%, 100 mW, 0402 [1005 Metric], Thick Film, Precision" (at 0 0 0)
        (effects (font (size 1.27 1.27)) hide)
      )
      (symbol "R_63R4_0402_0_1"
        (rectangle (start 0.635 0.889) (end 4.445 -0.889)
          (stroke (width 0.254) (type default))
          (fill (type none))
        )
      )
      (symbol "R_63R4_0402_1_1"
        (pin passive line (at 0 0 0) (length 0.635)
          (name "~" (effects (font (size 1.27 1.27))))
          (number "1" (effects (font (size 1.27 1.27))))
        )
        (pin passive line (at 5.08 0 180) (length 0.635)
          (name "~" (effects (font (size 1.27 1.27))))
          (number "2" (effects (font (size 1.27 1.27))))
        )
      )
    )
	(symbol "scalenode-cm4-baseboard:R_75R_0402" (pin_numbers hide) (pin_names hide) (in_bom yes) (on_board yes)
      (property "Reference" "R" (at 20.32 -5.08 0)
        (effects (font (size 1.27 1.27) (thickness 0.15)) (justify left bottom))
      )
      (property "Value" "R_75R_0402" (at 20.32 -12.7 0)
        (effects (font (size 1.27 1.27) (thickness 0.15)) (justify left bottom) hide)
      )
      (property "Footprint" "scalenode-cm4-baseboard-footprints:R_0402_1005Metric" (at 20.32 -15.24 0)
        (effects (font (size 1.27 1.27) (thickness 0.15)) (justify left bottom) hide)
      )
      (property "Datasheet" "https://www.bourns.com/docs/product-datasheets/cr.pdf" (at 20.32 -17.78 0)
        (effects (font (size 1.27 1.27) (thickness 0.15)) (justify left bottom) hide)
      )
      (property "MPN" "CR0402-FX-75R0GLF" (at 20.32 -20.32 0)
        (effects (font (size 1.27 1.27) (thickness 0.15)) (justify left bottom) hide)
      )
      (property "Manufacturer" "Bourns" (at 20.32 -22.86 0)
        (effects (font (size 1.27 1.27) (thickness 0.15)) (justify left bottom) hide)
      )
      (property "License" "Apache-2.0" (at 20.32 -25.4 0)
        (effects (font (size 1.27 1.27) (thickness 0.15)) (justify left bottom) hide)
      )
      (property "Author" "Antmicro" (at 20.32 -27.94 0)
        (effects (font (size 1.27 1.27) (thickness 0.15)) (justify left bottom) hide)
      )
      (property "Val" "75R" (at 20.32 -7.62 0)
        (effects (font (size 1.27 1.27) (thickness 0.15)) (justify left bottom))
      )
      (property "Tolerance" "1%" (at 20.32 -10.16 0)
        (effects (font (size 1.27 1.27)) (justify left bottom) hide)
      )
      (property "ki_description" "SMD Chip Resistor, 75 ohm, ± 1%, 62.5 mW, 0402 [1005 Metric], Thick Film, General Purpose" (at 0 0 0)
        (effects (font (size 1.27 1.27)) hide)
      )
      (symbol "R_75R_0402_0_1"
        (rectangle (start 0.635 0.889) (end 4.445 -0.889)
          (stroke (width 0.254) (type default))
          (fill (type none))
        )
      )
      (symbol "R_75R_0402_1_1"
        (pin passive line (at 0 0 0) (length 0.635)
          (name "~" (effects (font (size 1.27 1.27))))
          (number "1" (effects (font (size 1.27 1.27))))
        )
        (pin passive line (at 5.08 0 180) (length 0.635)
          (name "~" (effects (font (size 1.27 1.27))))
          (number "2" (effects (font (size 1.27 1.27))))
        )
      )
    )
	(symbol "scalenode-cm4-baseboard:SMAJ58A-13-F" (pin_names hide) (in_bom yes) (on_board yes)
      (property "Reference" "D" (at 21.59 -5.08 0)
        (effects (font (size 1.27 1.27) (thickness 0.15)) (justify left bottom))
      )
      (property "Value" "SMAJ58A-13-F" (at 21.59 -7.62 0)
        (effects (font (size 1.27 1.27) (thickness 0.15)) (justify left bottom))
      )
      (property "Footprint" "scalenode-cm4-baseboard-footprints:DO-214AC" (at 21.59 -10.16 0)
        (effects (font (size 1.27 1.27) (thickness 0.15)) (justify left bottom) hide)
      )
      (property "Datasheet" "https://4donline.ihs.com/images/VipMasterIC/IC/DIOD/DIOD-S-A0001754755/DIOD-S-A0001754755-1.pdf?hkey=52A5661711E402568146F3353EA87419" (at 21.59 -12.7 0)
        (effects (font (size 1.27 1.27) (thickness 0.15)) (justify left bottom) hide)
      )
      (property "MPN" "SMAJ58A-13-F" (at 21.59 -15.24 0)
        (effects (font (size 1.27 1.27) (thickness 0.15)) (justify left bottom) hide)
      )
      (property "Manufacturer" "Diodes Incorporated" (at 21.59 -17.78 0)
        (effects (font (size 1.27 1.27) (thickness 0.15)) (justify left bottom) hide)
      )
      (property "Author" "Antmicro" (at 21.59 -20.32 0)
        (effects (font (size 1.27 1.27) (thickness 0.15)) (justify left bottom) hide)
      )
      (property "License" "Apache-2.0" (at 21.59 -22.86 0)
        (effects (font (size 1.27 1.27) (thickness 0.15)) (justify left bottom) hide)
      )
      (symbol "SMAJ58A-13-F_0_1"
        (polyline
          (pts
            (xy 6.35 0)
            (xy 5.08 0)
          )
          (stroke (width 0.254) (type default))
          (fill (type none))
        )
      )
      (symbol "SMAJ58A-13-F_1_1"
        (polyline
          (pts
            (xy 5.08 1.27)
            (xy 5.08 -1.27)
          )
          (stroke (width 0.254) (type default))
          (fill (type none))
        )
        (polyline
          (pts
            (xy 2.54 1.27)
            (xy 2.54 -1.27)
            (xy 5.08 0)
            (xy 2.54 1.27)
          )
          (stroke (width 0.254) (type default))
          (fill (type outline))
        )
        (polyline
          (pts
            (xy 5.08 -1.27)
            (xy 5.08 -1.905)
            (xy 5.715 -1.905)
            (xy 5.715 -1.27)
          )
          (stroke (width 0.254) (type default))
          (fill (type none))
        )
        (polyline
          (pts
            (xy 5.08 1.27)
            (xy 5.08 1.905)
            (xy 4.445 1.905)
            (xy 4.445 1.27)
          )
          (stroke (width 0.254) (type default))
          (fill (type none))
        )
        (pin passive line (at 0 0 0) (length 2.54)
          (name "A" (effects (font (size 1.27 1.27))))
          (number "A" (effects (font (size 1.27 1.27))))
        )
        (pin passive line (at 8.89 0 180) (length 2.54)
          (name "K" (effects (font (size 1.27 1.27))))
          (number "K" (effects (font (size 1.27 1.27))))
        )
      )
    )
	(symbol "scalenode-cm4-baseboard:SMAJ6.5A" (pin_names hide) (in_bom yes) (on_board yes)
      (property "Reference" "D" (at 21.59 -5.08 0)
        (effects (font (size 1.27 1.27) (thickness 0.15)) (justify left bottom))
      )
      (property "Value" "SMAJ6.5A" (at 21.59 -7.62 0)
        (effects (font (size 1.27 1.27) (thickness 0.15)) (justify left bottom))
      )
      (property "Footprint" "scalenode-cm4-baseboard-footprints:DO-214AC" (at 21.59 -10.16 0)
        (effects (font (size 1.27 1.27) (thickness 0.15)) (justify left bottom) hide)
      )
      (property "Datasheet" "http://www.farnell.com/datasheets/2794252.pdf" (at 21.59 -12.7 0)
        (effects (font (size 1.27 1.27) (thickness 0.15)) (justify left bottom) hide)
      )
      (property "MPN" "SMAJ6.5A" (at 21.59 -15.24 0)
        (effects (font (size 1.27 1.27) (thickness 0.15)) (justify left bottom) hide)
      )
      (property "Manufacturer" "YAGEO" (at 21.59 -17.78 0)
        (effects (font (size 1.27 1.27) (thickness 0.15)) (justify left bottom) hide)
      )
      (property "Author" "Antmicro" (at 21.59 -20.32 0)
        (effects (font (size 1.27 1.27) (thickness 0.15)) (justify left bottom) hide)
      )
      (property "License" "Apache-2.0" (at 21.59 -22.86 0)
        (effects (font (size 1.27 1.27) (thickness 0.15)) (justify left bottom) hide)
      )
      (symbol "SMAJ6.5A_1_1"
        (polyline
          (pts
            (xy 5.08 1.27)
            (xy 5.08 -1.27)
          )
          (stroke (width 0.254) (type default))
          (fill (type none))
        )
        (polyline
          (pts
            (xy 2.54 1.27)
            (xy 2.54 -1.27)
            (xy 5.08 0)
            (xy 2.54 1.27)
          )
          (stroke (width 0.254) (type default))
          (fill (type none))
        )
        (polyline
          (pts
            (xy 5.08 -1.27)
            (xy 5.08 -1.905)
            (xy 5.715 -1.905)
            (xy 5.715 -1.27)
          )
          (stroke (width 0.254) (type default))
          (fill (type none))
        )
        (polyline
          (pts
            (xy 5.08 1.27)
            (xy 5.08 1.905)
            (xy 4.445 1.905)
            (xy 4.445 1.27)
          )
          (stroke (width 0.254) (type default))
          (fill (type none))
        )
        (pin passive line (at 0 0 0) (length 2.54)
          (name "A" (effects (font (size 1.27 1.27))))
          (number "A" (effects (font (size 1.27 1.27))))
        )
        (pin passive line (at 7.62 0 180) (length 2.54)
          (name "K" (effects (font (size 1.27 1.27))))
          (number "K" (effects (font (size 1.27 1.27))))
        )
      )
    )
	(symbol "scalenode-cm4-baseboard:SP3011-06UTG" (pin_names hide) (in_bom yes) (on_board yes)
      (property "Reference" "D" (at 13.97 -3.81 0)
        (effects (font (size 1.27 1.27) (thickness 0.15)) (justify left bottom))
      )
      (property "Value" "SP3011-06UTG" (at 13.97 -8.89 0)
        (effects (font (size 1.27 1.27) (thickness 0.15)) (justify left bottom) hide)
      )
      (property "Footprint" "scalenode-cm4-baseboard-footprints:USON-14_3.5x1.35_P0.5mm" (at 13.97 -11.43 0)
        (effects (font (size 1.27 1.27) (thickness 0.15)) (justify left bottom) hide)
      )
      (property "Datasheet" "https://www.littelfuse.com/media?resourcetype=datasheets&itemid=c9002a97-9994-449b-b722-f45ab5538c7f&filename=littelfuse-tvs-diode-array-sp3011-datasheet" (at 13.97 -13.97 0)
        (effects (font (size 1.27 1.27) (thickness 0.15)) (justify left bottom) hide)
      )
      (property "MPN" "SP3011-06UTG" (at 13.97 -6.35 0)
        (effects (font (size 1.27 1.27) (thickness 0.15)) (justify left bottom))
      )
      (property "Manufacturer" "Littelfuse" (at 13.97 -16.51 0)
        (effects (font (size 1.27 1.27) (thickness 0.15)) (justify left bottom) hide)
      )
      (property "Author" "Antmicro" (at 13.97 -19.05 0)
        (effects (font (size 1.27 1.27) (thickness 0.15)) (justify left bottom) hide)
      )
      (property "License" "Apache-2.0" (at 13.97 -21.59 0)
        (effects (font (size 1.27 1.27) (thickness 0.15)) (justify left bottom) hide)
      )
      (symbol "SP3011-06UTG_0_0"
        (pin passive line (at 0 -5.08 0) (length 2.54)
          (name "~" (effects (font (size 1.27 1.27))))
          (number "11" (effects (font (size 1.27 1.27))))
        )
        (pin passive line (at 0 -7.62 0) (length 2.54)
          (name "~" (effects (font (size 1.27 1.27))))
          (number "12" (effects (font (size 1.27 1.27))))
        )
        (pin passive line (at 0 -10.16 0) (length 2.54)
          (name "~" (effects (font (size 1.27 1.27))))
          (number "13" (effects (font (size 1.27 1.27))))
        )
        (pin passive line (at 0 -12.7 0) (length 2.54)
          (name "~" (effects (font (size 1.27 1.27))))
          (number "14" (effects (font (size 1.27 1.27))))
        )
      )
      (symbol "SP3011-06UTG_1_1"
        (polyline
          (pts
            (xy 2.54 -12.7)
            (xy 7.62 -12.7)
          )
          (stroke (width 0.254) (type default))
          (fill (type background))
        )
        (polyline
          (pts
            (xy 2.54 -10.16)
            (xy 7.62 -10.16)
          )
          (stroke (width 0.254) (type default))
          (fill (type background))
        )
        (polyline
          (pts
            (xy 2.54 -7.62)
            (xy 7.62 -7.62)
          )
          (stroke (width 0.254) (type default))
          (fill (type background))
        )
        (polyline
          (pts
            (xy 2.54 -5.08)
            (xy 7.62 -5.08)
          )
          (stroke (width 0.254) (type default))
          (fill (type background))
        )
        (polyline
          (pts
            (xy 2.54 -2.54)
            (xy 7.62 -2.54)
          )
          (stroke (width 0.254) (type default))
          (fill (type background))
        )
        (polyline
          (pts
            (xy 2.54 0)
            (xy 7.62 0)
          )
          (stroke (width 0.254) (type default))
          (fill (type background))
        )
        (polyline
          (pts
            (xy 7.62 -15.24)
            (xy 2.54 -15.24)
          )
          (stroke (width 0.254) (type default))
          (fill (type background))
        )
        (polyline
          (pts
            (xy 7.62 0)
            (xy 7.62 -15.24)
          )
          (stroke (width 0.254) (type default))
          (fill (type background))
        )
        (polyline
          (pts
            (xy 4.826 -13.335)
            (xy 5.08 -13.081)
            (xy 5.08 -12.319)
            (xy 5.334 -12.065)
          )
          (stroke (width 0.254) (type default))
          (fill (type background))
        )
        (polyline
          (pts
            (xy 4.826 -10.795)
            (xy 5.08 -10.541)
            (xy 5.08 -9.779)
            (xy 5.334 -9.525)
          )
          (stroke (width 0.254) (type default))
          (fill (type background))
        )
        (polyline
          (pts
            (xy 4.826 -8.255)
            (xy 5.08 -8.001)
            (xy 5.08 -7.239)
            (xy 5.334 -6.985)
          )
          (stroke (width 0.254) (type default))
          (fill (type background))
        )
        (polyline
          (pts
            (xy 4.826 -5.715)
            (xy 5.08 -5.461)
            (xy 5.08 -4.699)
            (xy 5.334 -4.445)
          )
          (stroke (width 0.254) (type default))
          (fill (type background))
        )
        (polyline
          (pts
            (xy 4.826 -3.175)
            (xy 5.08 -2.921)
            (xy 5.08 -2.159)
            (xy 5.334 -1.905)
          )
          (stroke (width 0.254) (type default))
          (fill (type background))
        )
        (polyline
          (pts
            (xy 4.826 -0.635)
            (xy 5.08 -0.381)
            (xy 5.08 0.381)
            (xy 5.334 0.635)
          )
          (stroke (width 0.254) (type default))
          (fill (type background))
        )
        (polyline
          (pts
            (xy 5.08 -12.7)
            (xy 3.81 -13.335)
            (xy 3.81 -12.065)
            (xy 5.08 -12.7)
          )
          (stroke (width 0.254) (type default))
          (fill (type background))
        )
        (polyline
          (pts
            (xy 5.08 -10.16)
            (xy 3.81 -10.795)
            (xy 3.81 -9.525)
            (xy 5.08 -10.16)
          )
          (stroke (width 0.254) (type default))
          (fill (type background))
        )
        (polyline
          (pts
            (xy 5.08 -10.16)
            (xy 6.35 -9.525)
            (xy 6.35 -10.795)
            (xy 5.08 -10.16)
          )
          (stroke (width 0.254) (type default))
          (fill (type background))
        )
        (polyline
          (pts
            (xy 5.08 -7.62)
            (xy 3.81 -8.255)
            (xy 3.81 -6.985)
            (xy 5.08 -7.62)
          )
          (stroke (width 0.254) (type default))
          (fill (type background))
        )
        (polyline
          (pts
            (xy 5.08 -5.08)
            (xy 3.81 -5.715)
            (xy 3.81 -4.445)
            (xy 5.08 -5.08)
          )
          (stroke (width 0.254) (type default))
          (fill (type background))
        )
        (polyline
          (pts
            (xy 5.08 -5.08)
            (xy 6.35 -4.445)
            (xy 6.35 -5.715)
            (xy 5.08 -5.08)
          )
          (stroke (width 0.254) (type default))
          (fill (type background))
        )
        (polyline
          (pts
            (xy 5.08 -2.54)
            (xy 3.81 -3.175)
            (xy 3.81 -1.905)
            (xy 5.08 -2.54)
          )
          (stroke (width 0.254) (type default))
          (fill (type background))
        )
        (polyline
          (pts
            (xy 5.08 -2.54)
            (xy 6.35 -3.175)
            (xy 6.35 -1.905)
            (xy 5.08 -2.54)
          )
          (stroke (width 0.254) (type default))
          (fill (type background))
        )
        (polyline
          (pts
            (xy 5.08 0)
            (xy 3.81 -0.635)
            (xy 3.81 0.635)
            (xy 5.08 0)
          )
          (stroke (width 0.254) (type default))
          (fill (type background))
        )
        (polyline
          (pts
            (xy 5.08 0)
            (xy 6.35 -0.635)
            (xy 6.35 0.635)
            (xy 5.08 0)
          )
          (stroke (width 0.254) (type default))
          (fill (type background))
        )
        (polyline
          (pts
            (xy 6.35 -12.065)
            (xy 6.35 -13.335)
            (xy 5.08 -12.7)
            (xy 6.35 -12.065)
          )
          (stroke (width 0.254) (type default))
          (fill (type background))
        )
        (polyline
          (pts
            (xy 6.35 -6.985)
            (xy 6.35 -8.255)
            (xy 5.08 -7.62)
            (xy 6.35 -6.985)
          )
          (stroke (width 0.254) (type default))
          (fill (type background))
        )
        (rectangle (start 2.54 2.54) (end 8.89 -17.78)
          (stroke (width 0.254) (type default))
          (fill (type background))
        )
        (circle (center 7.62 -12.7) (radius 0.254)
          (stroke (width 0.254) (type default))
          (fill (type background))
        )
        (circle (center 7.62 -10.16) (radius 0.254)
          (stroke (width 0.254) (type default))
          (fill (type background))
        )
        (circle (center 7.62 -10.16) (radius 0.254)
          (stroke (width 0.254) (type default))
          (fill (type background))
        )
        (circle (center 7.62 -7.62) (radius 0.254)
          (stroke (width 0.254) (type default))
          (fill (type background))
        )
        (circle (center 7.62 -5.08) (radius 0.254)
          (stroke (width 0.254) (type default))
          (fill (type background))
        )
        (circle (center 7.62 -5.08) (radius 0.254)
          (stroke (width 0.254) (type default))
          (fill (type background))
        )
        (circle (center 7.62 -2.54) (radius 0.254)
          (stroke (width 0.254) (type default))
          (fill (type background))
        )
        (pin passive line (at 0 -12.7 0) (length 2.54) hide
          (name "~" (effects (font (size 1.27 1.27))))
          (number "1" (effects (font (size 1.27 1.27))))
        )
        (pin passive line (at 0 -15.24 0) (length 2.54)
          (name "~" (effects (font (size 1.27 1.27))))
          (number "10" (effects (font (size 1.27 1.27))))
        )
        (pin passive line (at 0 -10.16 0) (length 2.54) hide
          (name "~" (effects (font (size 1.27 1.27))))
          (number "2" (effects (font (size 1.27 1.27))))
        )
        (pin passive line (at 0 -7.62 0) (length 2.54) hide
          (name "~" (effects (font (size 1.27 1.27))))
          (number "3" (effects (font (size 1.27 1.27))))
        )
        (pin passive line (at 0 -5.08 0) (length 2.54) hide
          (name "~" (effects (font (size 1.27 1.27))))
          (number "4" (effects (font (size 1.27 1.27))))
        )
        (pin passive line (at 0 -15.24 0) (length 2.54) hide
          (name "~" (effects (font (size 1.27 1.27))))
          (number "5" (effects (font (size 1.27 1.27))))
        )
        (pin passive line (at 0 -2.54 0) (length 2.54) hide
          (name "~" (effects (font (size 1.27 1.27))))
          (number "6" (effects (font (size 1.27 1.27))))
        )
        (pin passive line (at 0 0 0) (length 2.54) hide
          (name "~" (effects (font (size 1.27 1.27))))
          (number "7" (effects (font (size 1.27 1.27))))
        )
        (pin passive line (at 0 0 0) (length 2.54)
          (name "~" (effects (font (size 1.27 1.27))))
          (number "8" (effects (font (size 1.27 1.27))))
        )
        (pin passive line (at 0 -2.54 0) (length 2.54)
          (name "~" (effects (font (size 1.27 1.27))))
          (number "9" (effects (font (size 1.27 1.27))))
        )
      )
    )
	(symbol "scalenode-cm4-baseboard:SS-74800-144" (in_bom yes) (on_board yes)
      (property "Reference" "J" (at 33.02 -2.54 0)
        (effects (font (size 1.27 1.27) (thickness 0.15)) (justify left bottom))
      )
      (property "Value" "SS-74800-144" (at 33.02 -7.62 0)
        (effects (font (size 1.27 1.27) (thickness 0.15)) (justify left bottom) hide)
      )
      (property "Footprint" "scalenode-cm4-baseboard-footprints:Ethernet_Jack_SS-74800-144" (at 33.02 -10.16 0)
        (effects (font (size 1.27 1.27) (thickness 0.15)) (justify left bottom) hide)
      )
      (property "Datasheet" "https://www.belfuse.com/resources/drawings/stewartconnector/dr-STW-SS-74800-144.pdf" (at 33.02 -12.7 0)
        (effects (font (size 1.27 1.27) (thickness 0.15)) (justify left bottom) hide)
      )
      (property "MPN" "SS-74800-144" (at 33.02 -5.08 0)
        (effects (font (size 1.27 1.27) (thickness 0.15)) (justify left bottom))
      )
      (property "Manufacturer" "Bel" (at 33.02 -15.24 0)
        (effects (font (size 1.27 1.27) (thickness 0.15)) (justify left bottom) hide)
      )
      (property "Author" "Antmicro" (at 33.02 -17.78 0)
        (effects (font (size 1.27 1.27) (thickness 0.15)) (justify left bottom) hide)
      )
      (property "License" "Apache-2.0" (at 33.02 -20.32 0)
        (effects (font (size 1.27 1.27) (thickness 0.15)) (justify left bottom) hide)
      )
      (property "ki_keywords" "CONNECTOR" (at 0 0 0)
        (effects (font (size 1.27 1.27)) hide)
      )
      (property "ki_description" "Jack Modular Connector 8p8c (RJ45, Ethernet) 90° Angle (Right) Shielded, EMI Finger Cat5e" (at 0 0 0)
        (effects (font (size 1.27 1.27)) hide)
      )
      (symbol "SS-74800-144_1_1"
        (polyline
          (pts
            (xy 8.89 -27.94)
            (xy 6.35 -27.94)
          )
          (stroke (width 0.254) (type default))
          (fill (type background))
        )
        (polyline
          (pts
            (xy 8.89 0)
            (xy 6.35 0)
          )
          (stroke (width 0.254) (type default))
          (fill (type background))
        )
        (polyline
          (pts
            (xy 10.16 -27.94)
            (xy 12.7 -27.94)
          )
          (stroke (width 0.254) (type default))
          (fill (type background))
        )
        (polyline
          (pts
            (xy 10.16 -25.908)
            (xy 10.16 -26.416)
          )
          (stroke (width 0.254) (type default))
          (fill (type background))
        )
        (polyline
          (pts
            (xy 10.16 -2.032)
            (xy 10.16 -1.524)
          )
          (stroke (width 0.254) (type default))
          (fill (type background))
        )
        (polyline
          (pts
            (xy 10.16 0)
            (xy 12.7 0)
          )
          (stroke (width 0.254) (type default))
          (fill (type background))
        )
        (polyline
          (pts
            (xy 10.414 -27.178)
            (xy 10.414 -28.702)
          )
          (stroke (width 0.254) (type default))
          (fill (type background))
        )
        (polyline
          (pts
            (xy 10.414 -0.762)
            (xy 10.414 0.762)
          )
          (stroke (width 0.254) (type default))
          (fill (type background))
        )
        (polyline
          (pts
            (xy 11.176 -25.908)
            (xy 11.176 -26.416)
          )
          (stroke (width 0.254) (type default))
          (fill (type background))
        )
        (polyline
          (pts
            (xy 11.176 -2.032)
            (xy 11.176 -1.524)
          )
          (stroke (width 0.254) (type default))
          (fill (type background))
        )
        (polyline
          (pts
            (xy 9.144 -26.67)
            (xy 9.398 -26.67)
            (xy 10.16 -25.908)
            (xy 9.652 -25.908)
          )
          (stroke (width 0.254) (type default))
          (fill (type background))
        )
        (polyline
          (pts
            (xy 9.144 -1.27)
            (xy 9.398 -1.27)
            (xy 10.16 -2.032)
            (xy 9.652 -2.032)
          )
          (stroke (width 0.254) (type default))
          (fill (type background))
        )
        (polyline
          (pts
            (xy 10.16 -27.94)
            (xy 8.89 -27.178)
            (xy 8.89 -28.702)
            (xy 10.16 -27.94)
          )
          (stroke (width 0.254) (type default))
          (fill (type background))
        )
        (polyline
          (pts
            (xy 10.16 -26.67)
            (xy 10.414 -26.67)
            (xy 11.176 -25.908)
            (xy 10.668 -25.908)
          )
          (stroke (width 0.254) (type default))
          (fill (type background))
        )
        (polyline
          (pts
            (xy 10.16 -1.27)
            (xy 10.414 -1.27)
            (xy 11.176 -2.032)
            (xy 10.668 -2.032)
          )
          (stroke (width 0.254) (type default))
          (fill (type background))
        )
        (polyline
          (pts
            (xy 10.16 0)
            (xy 8.89 -0.762)
            (xy 8.89 0.762)
            (xy 10.16 0)
          )
          (stroke (width 0.254) (type default))
          (fill (type background))
        )
        (polyline
          (pts
            (xy 7.62 -10.16)
            (xy 7.62 -17.78)
            (xy 15.24 -17.78)
            (xy 15.24 -10.16)
            (xy 7.62 -10.16)
          )
          (stroke (width 0.254) (type default))
          (fill (type background))
        )
        (polyline
          (pts
            (xy 8.89 -12.7)
            (xy 8.89 -16.51)
            (xy 13.97 -16.51)
            (xy 13.97 -12.7)
            (xy 12.7 -12.7)
            (xy 12.7 -11.43)
            (xy 10.16 -11.43)
            (xy 10.16 -12.7)
            (xy 8.89 -12.7)
          )
          (stroke (width 0.254) (type default))
          (fill (type background))
        )
        (rectangle (start 2.54 2.54) (end 16.51 -30.48)
          (stroke (width 0.254) (type default))
          (fill (type background))
        )
        (text "G" (at 11.43 -2.54 0)
          (effects (font (size 1.27 1.27) (thickness 0.15)) (justify left bottom))
        )
        (text "Y" (at 11.43 -27.94 0)
          (effects (font (size 1.27 1.27) (thickness 0.15)) (justify left bottom))
        )
        (pin passive line (at 0 -5.08 0) (length 2.54)
          (name "~" (effects (font (size 1.27 1.27))))
          (number "1" (effects (font (size 1.27 1.27))))
        )
        (pin passive line (at 0 -27.94 0) (length 2.54)
          (name "10" (effects (font (size 1.27 1.27))))
          (number "10" (effects (font (size 1.27 1.27))))
        )
        (pin passive line (at 19.05 0 180) (length 2.54)
          (name "11" (effects (font (size 1.27 1.27))))
          (number "11" (effects (font (size 1.27 1.27))))
        )
        (pin passive line (at 0 0 0) (length 2.54)
          (name "12" (effects (font (size 1.27 1.27))))
          (number "12" (effects (font (size 1.27 1.27))))
        )
        (pin passive line (at 0 -7.62 0) (length 2.54)
          (name "~" (effects (font (size 1.27 1.27))))
          (number "2" (effects (font (size 1.27 1.27))))
        )
        (pin passive line (at 0 -10.16 0) (length 2.54)
          (name "~" (effects (font (size 1.27 1.27))))
          (number "3" (effects (font (size 1.27 1.27))))
        )
        (pin passive line (at 0 -12.7 0) (length 2.54)
          (name "~" (effects (font (size 1.27 1.27))))
          (number "4" (effects (font (size 1.27 1.27))))
        )
        (pin passive line (at 0 -15.24 0) (length 2.54)
          (name "~" (effects (font (size 1.27 1.27))))
          (number "5" (effects (font (size 1.27 1.27))))
        )
        (pin passive line (at 0 -17.78 0) (length 2.54)
          (name "~" (effects (font (size 1.27 1.27))))
          (number "6" (effects (font (size 1.27 1.27))))
        )
        (pin passive line (at 0 -20.32 0) (length 2.54)
          (name "~" (effects (font (size 1.27 1.27))))
          (number "7" (effects (font (size 1.27 1.27))))
        )
        (pin passive line (at 0 -22.86 0) (length 2.54)
          (name "~" (effects (font (size 1.27 1.27))))
          (number "8" (effects (font (size 1.27 1.27))))
        )
        (pin passive line (at 19.05 -27.94 180) (length 2.54)
          (name "9" (effects (font (size 1.27 1.27))))
          (number "9" (effects (font (size 1.27 1.27))))
        )
        (pin passive line (at 19.05 -19.05 180) (length 2.54)
          (name "SHIELD" (effects (font (size 1.27 1.27))))
          (number "SH" (effects (font (size 1.27 1.27))))
        )
      )
    )
	(symbol "scalenode-cm4-baseboard:Socket_Hirose_DF40_2x50_DF40HC-3.0-100DS-0.4V" (in_bom yes) (on_board yes)
      (property "Reference" "J" (at 35.56 0 0)
        (effects (font (size 1.27 1.27) (thickness 0.15)) (justify left bottom))
      )
      (property "Value" "Socket_Hirose_DF40_2x50_DF40HC-3.0-100DS-0.4V" (at 35.56 -5.08 0)
        (effects (font (size 1.27 1.27) (thickness 0.15)) (justify left bottom) hide)
      )
      (property "Footprint" "scalenode-cm4-baseboard-footprints:Conn_Socket_Hirose_DF40_2x50_DF40HC-3.0-100DS-0.4V" (at 35.56 -7.62 0)
        (effects (font (size 1.27 1.27) (thickness 0.15)) (justify left bottom) hide)
      )
      (property "Datasheet" "https://www.hirose.com/en/product/document?clcode=CL0684-4151-0-51&productname=DF40HC(3.0)-100DS-0.4V(51&series=DF40&documenttype=Catalog&lang=en&documentid=en_DF40_CAT" (at 35.56 -10.16 0)
        (effects (font (size 1.27 1.27) (thickness 0.15)) (justify left bottom) hide)
      )
      (property "MPN" "DF40HC(3.0)-100DS-0.4V(51)" (at 35.56 -2.54 0)
        (effects (font (size 1.27 1.27) (thickness 0.15)) (justify left bottom))
      )
      (property "Manufacturer" "Hirose Electric" (at 35.56 -12.7 0)
        (effects (font (size 1.27 1.27) (thickness 0.15)) (justify left bottom) hide)
      )
      (property "Pitch" "0.4 mm" (at 35.56 -15.24 0)
        (effects (font (size 1.27 1.27)) (justify left bottom) hide)
      )
      (property "Author" "Antmicro" (at 35.56 -17.78 0)
        (effects (font (size 1.27 1.27) (thickness 0.15)) (justify left bottom) hide)
      )
      (property "License" "Apache-2.0" (at 35.56 -20.32 0)
        (effects (font (size 1.27 1.27) (thickness 0.15)) (justify left bottom) hide)
      )
      (property "ki_keywords" "CONNECTOR, B2B, SOCKET" (at 0 0 0)
        (effects (font (size 1.27 1.27)) hide)
      )
      (property "ki_description" "100 Position Connector Receptacle, Center Strip Contacts Surface Mount Gold" (at 0 0 0)
        (effects (font (size 1.27 1.27)) hide)
      )
      (symbol "Socket_Hirose_DF40_2x50_DF40HC-3.0-100DS-0.4V_1_1"
        (rectangle (start 3.81 2.54) (end 10.16 -127)
          (stroke (width 0.254) (type default))
          (fill (type background))
        )
        (rectangle (start 5.08 1.27) (end 8.89 -125.73)
          (stroke (width 0.254) (type default))
          (fill (type background))
        )
        (pin passive line (at 0 0 0) (length 3.81)
          (name "~" (effects (font (size 1.27 1.27))))
          (number "1" (effects (font (size 1.27 1.27))))
        )
        (pin passive line (at 13.97 -10.16 180) (length 3.81)
          (name "~" (effects (font (size 1.27 1.27))))
          (number "10" (effects (font (size 1.27 1.27))))
        )
        (pin passive line (at 13.97 -124.46 180) (length 3.81)
          (name "~" (effects (font (size 1.27 1.27))))
          (number "100" (effects (font (size 1.27 1.27))))
        )
        (pin passive line (at 0 -12.7 0) (length 3.81)
          (name "~" (effects (font (size 1.27 1.27))))
          (number "11" (effects (font (size 1.27 1.27))))
        )
        (pin passive line (at 13.97 -12.7 180) (length 3.81)
          (name "~" (effects (font (size 1.27 1.27))))
          (number "12" (effects (font (size 1.27 1.27))))
        )
        (pin passive line (at 0 -15.24 0) (length 3.81)
          (name "~" (effects (font (size 1.27 1.27))))
          (number "13" (effects (font (size 1.27 1.27))))
        )
        (pin passive line (at 13.97 -15.24 180) (length 3.81)
          (name "~" (effects (font (size 1.27 1.27))))
          (number "14" (effects (font (size 1.27 1.27))))
        )
        (pin passive line (at 0 -17.78 0) (length 3.81)
          (name "~" (effects (font (size 1.27 1.27))))
          (number "15" (effects (font (size 1.27 1.27))))
        )
        (pin passive line (at 13.97 -17.78 180) (length 3.81)
          (name "~" (effects (font (size 1.27 1.27))))
          (number "16" (effects (font (size 1.27 1.27))))
        )
        (pin passive line (at 0 -20.32 0) (length 3.81)
          (name "~" (effects (font (size 1.27 1.27))))
          (number "17" (effects (font (size 1.27 1.27))))
        )
        (pin passive line (at 13.97 -20.32 180) (length 3.81)
          (name "~" (effects (font (size 1.27 1.27))))
          (number "18" (effects (font (size 1.27 1.27))))
        )
        (pin passive line (at 0 -22.86 0) (length 3.81)
          (name "~" (effects (font (size 1.27 1.27))))
          (number "19" (effects (font (size 1.27 1.27))))
        )
        (pin passive line (at 13.97 0 180) (length 3.81)
          (name "~" (effects (font (size 1.27 1.27))))
          (number "2" (effects (font (size 1.27 1.27))))
        )
        (pin passive line (at 13.97 -22.86 180) (length 3.81)
          (name "~" (effects (font (size 1.27 1.27))))
          (number "20" (effects (font (size 1.27 1.27))))
        )
        (pin passive line (at 0 -25.4 0) (length 3.81)
          (name "~" (effects (font (size 1.27 1.27))))
          (number "21" (effects (font (size 1.27 1.27))))
        )
        (pin passive line (at 13.97 -25.4 180) (length 3.81)
          (name "~" (effects (font (size 1.27 1.27))))
          (number "22" (effects (font (size 1.27 1.27))))
        )
        (pin passive line (at 0 -27.94 0) (length 3.81)
          (name "~" (effects (font (size 1.27 1.27))))
          (number "23" (effects (font (size 1.27 1.27))))
        )
        (pin passive line (at 13.97 -27.94 180) (length 3.81)
          (name "~" (effects (font (size 1.27 1.27))))
          (number "24" (effects (font (size 1.27 1.27))))
        )
        (pin passive line (at 0 -30.48 0) (length 3.81)
          (name "~" (effects (font (size 1.27 1.27))))
          (number "25" (effects (font (size 1.27 1.27))))
        )
        (pin passive line (at 13.97 -30.48 180) (length 3.81)
          (name "~" (effects (font (size 1.27 1.27))))
          (number "26" (effects (font (size 1.27 1.27))))
        )
        (pin passive line (at 0 -33.02 0) (length 3.81)
          (name "~" (effects (font (size 1.27 1.27))))
          (number "27" (effects (font (size 1.27 1.27))))
        )
        (pin passive line (at 13.97 -33.02 180) (length 3.81)
          (name "~" (effects (font (size 1.27 1.27))))
          (number "28" (effects (font (size 1.27 1.27))))
        )
        (pin passive line (at 0 -35.56 0) (length 3.81)
          (name "~" (effects (font (size 1.27 1.27))))
          (number "29" (effects (font (size 1.27 1.27))))
        )
        (pin passive line (at 0 -2.54 0) (length 3.81)
          (name "~" (effects (font (size 1.27 1.27))))
          (number "3" (effects (font (size 1.27 1.27))))
        )
        (pin passive line (at 13.97 -35.56 180) (length 3.81)
          (name "~" (effects (font (size 1.27 1.27))))
          (number "30" (effects (font (size 1.27 1.27))))
        )
        (pin passive line (at 0 -38.1 0) (length 3.81)
          (name "~" (effects (font (size 1.27 1.27))))
          (number "31" (effects (font (size 1.27 1.27))))
        )
        (pin passive line (at 13.97 -38.1 180) (length 3.81)
          (name "~" (effects (font (size 1.27 1.27))))
          (number "32" (effects (font (size 1.27 1.27))))
        )
        (pin passive line (at 0 -40.64 0) (length 3.81)
          (name "~" (effects (font (size 1.27 1.27))))
          (number "33" (effects (font (size 1.27 1.27))))
        )
        (pin passive line (at 13.97 -40.64 180) (length 3.81)
          (name "~" (effects (font (size 1.27 1.27))))
          (number "34" (effects (font (size 1.27 1.27))))
        )
        (pin passive line (at 0 -43.18 0) (length 3.81)
          (name "~" (effects (font (size 1.27 1.27))))
          (number "35" (effects (font (size 1.27 1.27))))
        )
        (pin passive line (at 13.97 -43.18 180) (length 3.81)
          (name "~" (effects (font (size 1.27 1.27))))
          (number "36" (effects (font (size 1.27 1.27))))
        )
        (pin passive line (at 0 -45.72 0) (length 3.81)
          (name "~" (effects (font (size 1.27 1.27))))
          (number "37" (effects (font (size 1.27 1.27))))
        )
        (pin passive line (at 13.97 -45.72 180) (length 3.81)
          (name "~" (effects (font (size 1.27 1.27))))
          (number "38" (effects (font (size 1.27 1.27))))
        )
        (pin passive line (at 0 -48.26 0) (length 3.81)
          (name "~" (effects (font (size 1.27 1.27))))
          (number "39" (effects (font (size 1.27 1.27))))
        )
        (pin passive line (at 13.97 -2.54 180) (length 3.81)
          (name "~" (effects (font (size 1.27 1.27))))
          (number "4" (effects (font (size 1.27 1.27))))
        )
        (pin passive line (at 13.97 -48.26 180) (length 3.81)
          (name "~" (effects (font (size 1.27 1.27))))
          (number "40" (effects (font (size 1.27 1.27))))
        )
        (pin passive line (at 0 -50.8 0) (length 3.81)
          (name "~" (effects (font (size 1.27 1.27))))
          (number "41" (effects (font (size 1.27 1.27))))
        )
        (pin passive line (at 13.97 -50.8 180) (length 3.81)
          (name "~" (effects (font (size 1.27 1.27))))
          (number "42" (effects (font (size 1.27 1.27))))
        )
        (pin passive line (at 0 -53.34 0) (length 3.81)
          (name "~" (effects (font (size 1.27 1.27))))
          (number "43" (effects (font (size 1.27 1.27))))
        )
        (pin passive line (at 13.97 -53.34 180) (length 3.81)
          (name "~" (effects (font (size 1.27 1.27))))
          (number "44" (effects (font (size 1.27 1.27))))
        )
        (pin passive line (at 0 -55.88 0) (length 3.81)
          (name "~" (effects (font (size 1.27 1.27))))
          (number "45" (effects (font (size 1.27 1.27))))
        )
        (pin passive line (at 13.97 -55.88 180) (length 3.81)
          (name "~" (effects (font (size 1.27 1.27))))
          (number "46" (effects (font (size 1.27 1.27))))
        )
        (pin passive line (at 0 -58.42 0) (length 3.81)
          (name "~" (effects (font (size 1.27 1.27))))
          (number "47" (effects (font (size 1.27 1.27))))
        )
        (pin passive line (at 13.97 -58.42 180) (length 3.81)
          (name "~" (effects (font (size 1.27 1.27))))
          (number "48" (effects (font (size 1.27 1.27))))
        )
        (pin passive line (at 0 -60.96 0) (length 3.81)
          (name "~" (effects (font (size 1.27 1.27))))
          (number "49" (effects (font (size 1.27 1.27))))
        )
        (pin passive line (at 0 -5.08 0) (length 3.81)
          (name "~" (effects (font (size 1.27 1.27))))
          (number "5" (effects (font (size 1.27 1.27))))
        )
        (pin passive line (at 13.97 -60.96 180) (length 3.81)
          (name "~" (effects (font (size 1.27 1.27))))
          (number "50" (effects (font (size 1.27 1.27))))
        )
        (pin passive line (at 0 -63.5 0) (length 3.81)
          (name "~" (effects (font (size 1.27 1.27))))
          (number "51" (effects (font (size 1.27 1.27))))
        )
        (pin passive line (at 13.97 -63.5 180) (length 3.81)
          (name "~" (effects (font (size 1.27 1.27))))
          (number "52" (effects (font (size 1.27 1.27))))
        )
        (pin passive line (at 0 -66.04 0) (length 3.81)
          (name "~" (effects (font (size 1.27 1.27))))
          (number "53" (effects (font (size 1.27 1.27))))
        )
        (pin passive line (at 13.97 -66.04 180) (length 3.81)
          (name "~" (effects (font (size 1.27 1.27))))
          (number "54" (effects (font (size 1.27 1.27))))
        )
        (pin passive line (at 0 -68.58 0) (length 3.81)
          (name "~" (effects (font (size 1.27 1.27))))
          (number "55" (effects (font (size 1.27 1.27))))
        )
        (pin passive line (at 13.97 -68.58 180) (length 3.81)
          (name "~" (effects (font (size 1.27 1.27))))
          (number "56" (effects (font (size 1.27 1.27))))
        )
        (pin passive line (at 0 -71.12 0) (length 3.81)
          (name "~" (effects (font (size 1.27 1.27))))
          (number "57" (effects (font (size 1.27 1.27))))
        )
        (pin passive line (at 13.97 -71.12 180) (length 3.81)
          (name "~" (effects (font (size 1.27 1.27))))
          (number "58" (effects (font (size 1.27 1.27))))
        )
        (pin passive line (at 0 -73.66 0) (length 3.81)
          (name "~" (effects (font (size 1.27 1.27))))
          (number "59" (effects (font (size 1.27 1.27))))
        )
        (pin passive line (at 13.97 -5.08 180) (length 3.81)
          (name "~" (effects (font (size 1.27 1.27))))
          (number "6" (effects (font (size 1.27 1.27))))
        )
        (pin passive line (at 13.97 -73.66 180) (length 3.81)
          (name "~" (effects (font (size 1.27 1.27))))
          (number "60" (effects (font (size 1.27 1.27))))
        )
        (pin passive line (at 0 -76.2 0) (length 3.81)
          (name "~" (effects (font (size 1.27 1.27))))
          (number "61" (effects (font (size 1.27 1.27))))
        )
        (pin passive line (at 13.97 -76.2 180) (length 3.81)
          (name "~" (effects (font (size 1.27 1.27))))
          (number "62" (effects (font (size 1.27 1.27))))
        )
        (pin passive line (at 0 -78.74 0) (length 3.81)
          (name "~" (effects (font (size 1.27 1.27))))
          (number "63" (effects (font (size 1.27 1.27))))
        )
        (pin passive line (at 13.97 -78.74 180) (length 3.81)
          (name "~" (effects (font (size 1.27 1.27))))
          (number "64" (effects (font (size 1.27 1.27))))
        )
        (pin passive line (at 0 -81.28 0) (length 3.81)
          (name "~" (effects (font (size 1.27 1.27))))
          (number "65" (effects (font (size 1.27 1.27))))
        )
        (pin passive line (at 13.97 -81.28 180) (length 3.81)
          (name "~" (effects (font (size 1.27 1.27))))
          (number "66" (effects (font (size 1.27 1.27))))
        )
        (pin passive line (at 0 -83.82 0) (length 3.81)
          (name "~" (effects (font (size 1.27 1.27))))
          (number "67" (effects (font (size 1.27 1.27))))
        )
        (pin passive line (at 13.97 -83.82 180) (length 3.81)
          (name "~" (effects (font (size 1.27 1.27))))
          (number "68" (effects (font (size 1.27 1.27))))
        )
        (pin passive line (at 0 -86.36 0) (length 3.81)
          (name "~" (effects (font (size 1.27 1.27))))
          (number "69" (effects (font (size 1.27 1.27))))
        )
        (pin passive line (at 0 -7.62 0) (length 3.81)
          (name "~" (effects (font (size 1.27 1.27))))
          (number "7" (effects (font (size 1.27 1.27))))
        )
        (pin passive line (at 13.97 -86.36 180) (length 3.81)
          (name "~" (effects (font (size 1.27 1.27))))
          (number "70" (effects (font (size 1.27 1.27))))
        )
        (pin passive line (at 0 -88.9 0) (length 3.81)
          (name "~" (effects (font (size 1.27 1.27))))
          (number "71" (effects (font (size 1.27 1.27))))
        )
        (pin passive line (at 13.97 -88.9 180) (length 3.81)
          (name "~" (effects (font (size 1.27 1.27))))
          (number "72" (effects (font (size 1.27 1.27))))
        )
        (pin passive line (at 0 -91.44 0) (length 3.81)
          (name "~" (effects (font (size 1.27 1.27))))
          (number "73" (effects (font (size 1.27 1.27))))
        )
        (pin passive line (at 13.97 -91.44 180) (length 3.81)
          (name "~" (effects (font (size 1.27 1.27))))
          (number "74" (effects (font (size 1.27 1.27))))
        )
        (pin passive line (at 0 -93.98 0) (length 3.81)
          (name "~" (effects (font (size 1.27 1.27))))
          (number "75" (effects (font (size 1.27 1.27))))
        )
        (pin passive line (at 13.97 -93.98 180) (length 3.81)
          (name "~" (effects (font (size 1.27 1.27))))
          (number "76" (effects (font (size 1.27 1.27))))
        )
        (pin passive line (at 0 -96.52 0) (length 3.81)
          (name "~" (effects (font (size 1.27 1.27))))
          (number "77" (effects (font (size 1.27 1.27))))
        )
        (pin passive line (at 13.97 -96.52 180) (length 3.81)
          (name "~" (effects (font (size 1.27 1.27))))
          (number "78" (effects (font (size 1.27 1.27))))
        )
        (pin passive line (at 0 -99.06 0) (length 3.81)
          (name "~" (effects (font (size 1.27 1.27))))
          (number "79" (effects (font (size 1.27 1.27))))
        )
        (pin passive line (at 13.97 -7.62 180) (length 3.81)
          (name "~" (effects (font (size 1.27 1.27))))
          (number "8" (effects (font (size 1.27 1.27))))
        )
        (pin passive line (at 13.97 -99.06 180) (length 3.81)
          (name "~" (effects (font (size 1.27 1.27))))
          (number "80" (effects (font (size 1.27 1.27))))
        )
        (pin passive line (at 0 -101.6 0) (length 3.81)
          (name "~" (effects (font (size 1.27 1.27))))
          (number "81" (effects (font (size 1.27 1.27))))
        )
        (pin passive line (at 13.97 -101.6 180) (length 3.81)
          (name "~" (effects (font (size 1.27 1.27))))
          (number "82" (effects (font (size 1.27 1.27))))
        )
        (pin passive line (at 0 -104.14 0) (length 3.81)
          (name "~" (effects (font (size 1.27 1.27))))
          (number "83" (effects (font (size 1.27 1.27))))
        )
        (pin passive line (at 13.97 -104.14 180) (length 3.81)
          (name "~" (effects (font (size 1.27 1.27))))
          (number "84" (effects (font (size 1.27 1.27))))
        )
        (pin passive line (at 0 -106.68 0) (length 3.81)
          (name "~" (effects (font (size 1.27 1.27))))
          (number "85" (effects (font (size 1.27 1.27))))
        )
        (pin passive line (at 13.97 -106.68 180) (length 3.81)
          (name "~" (effects (font (size 1.27 1.27))))
          (number "86" (effects (font (size 1.27 1.27))))
        )
        (pin passive line (at 0 -109.22 0) (length 3.81)
          (name "~" (effects (font (size 1.27 1.27))))
          (number "87" (effects (font (size 1.27 1.27))))
        )
        (pin passive line (at 13.97 -109.22 180) (length 3.81)
          (name "~" (effects (font (size 1.27 1.27))))
          (number "88" (effects (font (size 1.27 1.27))))
        )
        (pin passive line (at 0 -111.76 0) (length 3.81)
          (name "~" (effects (font (size 1.27 1.27))))
          (number "89" (effects (font (size 1.27 1.27))))
        )
        (pin passive line (at 0 -10.16 0) (length 3.81)
          (name "~" (effects (font (size 1.27 1.27))))
          (number "9" (effects (font (size 1.27 1.27))))
        )
        (pin passive line (at 13.97 -111.76 180) (length 3.81)
          (name "~" (effects (font (size 1.27 1.27))))
          (number "90" (effects (font (size 1.27 1.27))))
        )
        (pin passive line (at 0 -114.3 0) (length 3.81)
          (name "~" (effects (font (size 1.27 1.27))))
          (number "91" (effects (font (size 1.27 1.27))))
        )
        (pin passive line (at 13.97 -114.3 180) (length 3.81)
          (name "~" (effects (font (size 1.27 1.27))))
          (number "92" (effects (font (size 1.27 1.27))))
        )
        (pin passive line (at 0 -116.84 0) (length 3.81)
          (name "~" (effects (font (size 1.27 1.27))))
          (number "93" (effects (font (size 1.27 1.27))))
        )
        (pin passive line (at 13.97 -116.84 180) (length 3.81)
          (name "~" (effects (font (size 1.27 1.27))))
          (number "94" (effects (font (size 1.27 1.27))))
        )
        (pin passive line (at 0 -119.38 0) (length 3.81)
          (name "~" (effects (font (size 1.27 1.27))))
          (number "95" (effects (font (size 1.27 1.27))))
        )
        (pin passive line (at 13.97 -119.38 180) (length 3.81)
          (name "~" (effects (font (size 1.27 1.27))))
          (number "96" (effects (font (size 1.27 1.27))))
        )
        (pin passive line (at 0 -121.92 0) (length 3.81)
          (name "~" (effects (font (size 1.27 1.27))))
          (number "97" (effects (font (size 1.27 1.27))))
        )
        (pin passive line (at 13.97 -121.92 180) (length 3.81)
          (name "~" (effects (font (size 1.27 1.27))))
          (number "98" (effects (font (size 1.27 1.27))))
        )
        (pin passive line (at 0 -124.46 0) (length 3.81)
          (name "~" (effects (font (size 1.27 1.27))))
          (number "99" (effects (font (size 1.27 1.27))))
        )
      )
    )
	(symbol "scalenode-cm4-baseboard:Spacer_Drill1mm_H4mm_97730406332R" (pin_names hide) (in_bom yes) (on_board yes)
      (property "Reference" "H" (at 15.24 -5.08 0)
        (effects (font (size 1.27 1.27) (thickness 0.15)) (justify left bottom))
      )
      (property "Value" "Spacer_Drill1mm_H4mm_97730406332R" (at 15.24 -10.16 0)
        (effects (font (size 1.27 1.27) (thickness 0.15)) (justify left bottom) hide)
      )
      (property "Footprint" "scalenode-cm4-baseboard-footprints:Spacer_Drill1mm_H4mm_97730406332R" (at 15.24 -12.7 0)
        (effects (font (size 1.27 1.27) (thickness 0.15)) (justify left bottom) hide)
      )
      (property "Datasheet" "https://www.we-online.com/components/products/datasheet/97730406332R.pdf" (at 15.24 -15.24 0)
        (effects (font (size 1.27 1.27) (thickness 0.15)) (justify left bottom) hide)
      )
      (property "MPN" "97730406332R " (at 15.24 -7.62 0)
        (effects (font (size 1.27 1.27) (thickness 0.15)) (justify left bottom))
      )
      (property "Manufacturer" "Würth Elektronik" (at 22.86 -12.7 0)
        (effects (font (size 1.27 1.27) (thickness 0.15)) (justify left bottom) hide)
      )
      (property "Author" "Antmicro" (at 15.24 -17.78 0)
        (effects (font (size 1.27 1.27) (thickness 0.15)) (justify left bottom) hide)
      )
      (property "License" "Apache-2.0" (at 15.24 -20.32 0)
        (effects (font (size 1.27 1.27) (thickness 0.15)) (justify left bottom) hide)
      )
      (symbol "Spacer_Drill1mm_H4mm_97730406332R_1_1"
        (rectangle (start 2.54 -2.54) (end 7.62 2.54)
          (stroke (width 0.254) (type default))
          (fill (type none))
        )
        (rectangle (start 3.81 -1.27) (end 6.35 1.27)
          (stroke (width 0.254) (type default))
          (fill (type none))
        )
        (pin passive line (at 0 0 0) (length 2.54)
          (name "1" (effects (font (size 1.27 1.27))))
          (number "1" (effects (font (size 1.27 1.27))))
        )
      )
    )
	(symbol "scalenode-cm4-baseboard:Spacer_Drill3.7mm_H3mm_9774030151R" (in_bom yes) (on_board yes)
      (property "Reference" "H" (at 22.86 -2.54 0)
        (effects (font (size 1.27 1.27) (thickness 0.15)) (justify left bottom))
      )
      (property "Value" "Spacer_Drill3.7mm_H3mm_9774030151R" (at 22.86 -5.08 0)
        (effects (font (size 1.27 1.27) (thickness 0.15)) (justify left bottom))
      )
      (property "Footprint" "scalenode-cm4-baseboard-footprints:Spacer_Drill3.7mm_H3mm_9774030151R" (at 22.86 -7.62 0)
        (effects (font (size 1.27 1.27) (thickness 0.15)) (justify left bottom) hide)
      )
      (property "Datasheet" "https://www.we-online.com/catalog/datasheet/9774030151.pdf" (at 22.86 -10.16 0)
        (effects (font (size 1.27 1.27) (thickness 0.15)) (justify left bottom) hide)
      )
      (property "Manufacturer" "Würth Elektronik" (at 22.86 -12.7 0)
        (effects (font (size 1.27 1.27) (thickness 0.15)) (justify left bottom) hide)
      )
      (property "MPN" "9774030151R" (at 22.86 -15.24 0)
        (effects (font (size 1.27 1.27) (thickness 0.15)) (justify left bottom) hide)
      )
      (property "Author" "Antmicro" (at 22.86 -17.78 0)
        (effects (font (size 1.27 1.27) (thickness 0.15)) (justify left bottom) hide)
      )
      (property "License" "Apache-2.0" (at 22.86 -20.32 0)
        (effects (font (size 1.27 1.27) (thickness 0.15)) (justify left bottom) hide)
      )
      (property "ki_keywords" "SPACER" (at 0 0 0)
        (effects (font (size 1.27 1.27)) hide)
      )
      (property "ki_description" "Spacer, SMT,  Steel, Swage Round, 5.1mmx3mm, M3 Thread, WA-SMSI Series" (at 0 0 0)
        (effects (font (size 1.27 1.27)) hide)
      )
      (symbol "Spacer_Drill3.7mm_H3mm_9774030151R_1_1"
        (rectangle (start 2.54 -2.54) (end 7.62 2.54)
          (stroke (width 0.254) (type default))
          (fill (type background))
        )
        (rectangle (start 3.81 -1.27) (end 6.35 1.27)
          (stroke (width 0.254) (type default))
          (fill (type background))
        )
        (pin passive line (at 0 0 0) (length 2.54)
          (name "~" (effects (font (size 1.27 1.27))))
          (number "1" (effects (font (size 1.27 1.27))))
        )
      )
    )
	(symbol "scalenode-cm4-baseboard:TPD4S012DRYR" (in_bom yes) (on_board yes)
      (property "Reference" "D" (at 30.48 -2.54 0)
        (effects (font (size 1.27 1.27) (thickness 0.15)) (justify left bottom))
      )
      (property "Value" "TPD4S012DRYR" (at 30.48 -15.24 0)
        (effects (font (size 1.27 1.27) (thickness 0.15)) (justify left bottom) hide)
      )
      (property "Footprint" "scalenode-cm4-baseboard-footprints:UFDFN-6_1.45x1mm" (at 30.48 -7.62 0)
        (effects (font (size 1.27 1.27) (thickness 0.15)) (justify left bottom) hide)
      )
      (property "Datasheet" "http://www.ti.com/general/docs/suppproductinfo.tsp?distId=10&gotoUrl=http%3A%2F%2Fwww.ti.com%2Flit%2Fgpn%2Ftpd4s012" (at 30.48 -10.16 0)
        (effects (font (size 1.27 1.27) (thickness 0.15)) (justify left bottom) hide)
      )
      (property "Manufacturer" "Texas Instruments" (at 30.48 -12.7 0)
        (effects (font (size 1.27 1.27) (thickness 0.15)) (justify left bottom) hide)
      )
      (property "MPN" "TPD4S012DRYR" (at 30.48 -5.08 0)
        (effects (font (size 1.27 1.27) (thickness 0.15)) (justify left bottom))
      )
      (property "Author" "Antmicro" (at 30.48 -17.78 0)
        (effects (font (size 1.27 1.27) (thickness 0.15)) (justify left bottom) hide)
      )
      (property "License" "Apache-2.0" (at 30.48 -20.32 0)
        (effects (font (size 1.27 1.27) (thickness 0.15)) (justify left bottom) hide)
      )
      (symbol "TPD4S012DRYR_1_1"
        (polyline
          (pts
            (xy 7.62 -3.81)
            (xy 6.985 -3.175)
          )
          (stroke (width 0.254) (type default))
          (fill (type none))
        )
        (polyline
          (pts
            (xy 7.62 -3.81)
            (xy 10.16 -3.81)
          )
          (stroke (width 0.254) (type default))
          (fill (type none))
        )
        (polyline
          (pts
            (xy 8.89 -6.35)
            (xy 8.89 -8.89)
          )
          (stroke (width 0.254) (type default))
          (fill (type none))
        )
        (polyline
          (pts
            (xy 8.89 -3.81)
            (xy 8.89 -1.27)
          )
          (stroke (width 0.254) (type default))
          (fill (type none))
        )
        (polyline
          (pts
            (xy 10.16 -3.81)
            (xy 10.795 -4.445)
          )
          (stroke (width 0.254) (type default))
          (fill (type none))
        )
        (polyline
          (pts
            (xy 7.62 -6.35)
            (xy 10.16 -6.35)
            (xy 8.89 -3.81)
            (xy 7.62 -6.35)
          )
          (stroke (width 0.254) (type default))
          (fill (type background))
        )
        (rectangle (start 2.54 2.54) (end 12.7 -12.7)
          (stroke (width 0.254) (type default))
          (fill (type background))
        )
        (pin input line (at 0 -2.54 0) (length 2.54)
          (name "D+" (effects (font (size 1.27 1.27))))
          (number "1" (effects (font (size 1.27 1.27))))
        )
        (pin output line (at 0 -5.08 0) (length 2.54)
          (name "D-" (effects (font (size 1.27 1.27))))
          (number "2" (effects (font (size 1.27 1.27))))
        )
        (pin input line (at 0 -7.62 0) (length 2.54)
          (name "ID" (effects (font (size 1.27 1.27))))
          (number "3" (effects (font (size 1.27 1.27))))
        )
        (pin power_in line (at 0 -10.16 0) (length 2.54)
          (name "GND" (effects (font (size 1.27 1.27))))
          (number "4" (effects (font (size 1.27 1.27))))
        )
        (pin no_connect line (at 15.24 0 180) (length 2.54) hide
          (name "NC" (effects (font (size 1.27 1.27))))
          (number "5" (effects (font (size 1.27 1.27))))
        )
        (pin power_in line (at 0 0 0) (length 2.54)
          (name "V_{BUS}" (effects (font (size 1.27 1.27))))
          (number "6" (effects (font (size 1.27 1.27))))
        )
      )
    )
	(symbol "scalenode-cm4-baseboard:TPS2373-3RGW" (in_bom yes) (on_board yes)
      (property "Reference" "U" (at 45.72 -2.54 0)
        (effects (font (size 1.27 1.27) (thickness 0.15)) (justify left bottom))
      )
      (property "Value" "TPS2373-3RGW" (at 45.72 -12.7 0)
        (effects (font (size 1.27 1.27) (thickness 0.15)) (justify left bottom) hide)
      )
      (property "Footprint" "scalenode-cm4-baseboard-footprints:VQFN-20_5x5x1mm_P0.65mm" (at 45.72 -7.62 0)
        (effects (font (size 1.27 1.27) (thickness 0.15)) (justify left bottom) hide)
      )
      (property "Datasheet" "https://www.ti.com/lit/ds/symlink/tps2373.pdf?ts=1659968389615&ref_url=https%253A%252F%252Fwww.ti.com%252Fpower-management%252Fpower-over-ethernet-poe%252Fpowered-devices%252Fproducts.html" (at 45.72 -10.16 0)
        (effects (font (size 1.27 1.27) (thickness 0.15)) (justify left bottom) hide)
      )
      (property "MPN" "TPS2373-3RGWR" (at 45.72 -5.08 0)
        (effects (font (size 1.27 1.27) (thickness 0.15)) (justify left bottom))
      )
      (property "Manufacturer" "Texas Instruments" (at 45.72 -15.24 0)
        (effects (font (size 1.27 1.27) (thickness 0.15)) (justify left bottom) hide)
      )
      (property "Author" "Antmicro" (at 45.72 -17.78 0)
        (effects (font (size 1.27 1.27) (thickness 0.15)) (justify left bottom) hide)
      )
      (property "License" "Apache-2.0" (at 45.72 -20.32 0)
        (effects (font (size 1.27 1.27) (thickness 0.15)) (justify left bottom) hide)
      )
      (property "ki_description" "Power distribution switch/load driver" (at 0 0 0)
        (effects (font (size 1.27 1.27)) hide)
      )
      (symbol "TPS2373-3RGW_1_1"
        (rectangle (start 2.54 -34.29) (end 27.94 2.54)
          (stroke (width 0.254) (type default))
          (fill (type background))
        )
        (pin power_in line (at 0 0 0) (length 2.54)
          (name "VDD" (effects (font (size 1.27 1.27))))
          (number "1" (effects (font (size 1.27 1.27))))
        )
        (pin input line (at 30.48 -19.05 180) (length 2.54)
          (name "APD" (effects (font (size 1.27 1.27))))
          (number "10" (effects (font (size 1.27 1.27))))
        )
        (pin power_out line (at 30.48 -24.13 180) (length 2.54)
          (name "RTN" (effects (font (size 1.27 1.27))))
          (number "11" (effects (font (size 1.27 1.27))))
        )
        (pin passive line (at 30.48 -24.13 180) (length 2.54) hide
          (name "RTN" (effects (font (size 1.27 1.27))))
          (number "12" (effects (font (size 1.27 1.27))))
        )
        (pin output line (at 30.48 -16.51 180) (length 2.54)
          (name "PG" (effects (font (size 1.27 1.27))))
          (number "13" (effects (font (size 1.27 1.27))))
        )
        (pin output line (at 30.48 -12.7 180) (length 2.54)
          (name "VC_OUT" (effects (font (size 1.27 1.27))))
          (number "14" (effects (font (size 1.27 1.27))))
        )
        (pin input line (at 30.48 -7.62 180) (length 2.54)
          (name "VC_IN" (effects (font (size 1.27 1.27))))
          (number "15" (effects (font (size 1.27 1.27))))
        )
        (pin output line (at 30.48 -31.75 180) (length 2.54)
          (name "UVLO_SEL" (effects (font (size 1.27 1.27))))
          (number "16" (effects (font (size 1.27 1.27))))
        )
        (pin output line (at 30.48 -2.54 180) (length 2.54)
          (name "TPL" (effects (font (size 1.27 1.27))))
          (number "17" (effects (font (size 1.27 1.27))))
        )
        (pin output line (at 30.48 0 180) (length 2.54)
          (name "TPH" (effects (font (size 1.27 1.27))))
          (number "18" (effects (font (size 1.27 1.27))))
        )
        (pin output line (at 30.48 -29.21 180) (length 2.54)
          (name "~{BT}" (effects (font (size 1.27 1.27))))
          (number "19" (effects (font (size 1.27 1.27))))
        )
        (pin input line (at 0 -2.54 0) (length 2.54)
          (name "DEN" (effects (font (size 1.27 1.27))))
          (number "2" (effects (font (size 1.27 1.27))))
        )
        (pin passive line (at 0 -20.32 0) (length 2.54) hide
          (name "VSS" (effects (font (size 1.27 1.27))))
          (number "21" (effects (font (size 1.27 1.27))))
        )
        (pin input line (at 0 -7.62 0) (length 2.54)
          (name "CLSA" (effects (font (size 1.27 1.27))))
          (number "3" (effects (font (size 1.27 1.27))))
        )
        (pin power_in line (at 0 -20.32 0) (length 2.54)
          (name "VSS" (effects (font (size 1.27 1.27))))
          (number "4" (effects (font (size 1.27 1.27))))
        )
        (pin passive line (at 0 -20.32 0) (length 2.54) hide
          (name "VSS" (effects (font (size 1.27 1.27))))
          (number "5" (effects (font (size 1.27 1.27))))
        )
        (pin input line (at 0 -10.16 0) (length 2.54)
          (name "CLSB" (effects (font (size 1.27 1.27))))
          (number "6" (effects (font (size 1.27 1.27))))
        )
        (pin input line (at 0 -29.21 0) (length 2.54)
          (name "REF" (effects (font (size 1.27 1.27))))
          (number "7" (effects (font (size 1.27 1.27))))
        )
        (pin input line (at 0 -25.4 0) (length 2.54)
          (name "AMPS_CTL" (effects (font (size 1.27 1.27))))
          (number "8" (effects (font (size 1.27 1.27))))
        )
        (pin input line (at 0 -31.75 0) (length 2.54)
          (name "MPS_DUTY" (effects (font (size 1.27 1.27))))
          (number "9" (effects (font (size 1.27 1.27))))
        )
      )
    )
	(symbol "scalenode-cm4-baseboard:TPS2378DDA" (in_bom yes) (on_board yes)
      (property "Reference" "U" (at 35.56 0 0)
        (effects (font (size 1.27 1.27) (thickness 0.15)) (justify left bottom))
      )
      (property "Value" "TPS2378DDA" (at 35.56 -2.54 0)
        (effects (font (size 1.27 1.27) (thickness 0.15)) (justify left bottom) hide)
      )
      (property "Footprint" "scalenode-cm4-baseboard-footprints:SOIC-8-1EP_3.9x4.9x1.75mm_P1.27mm" (at 35.56 -5.08 0)
        (effects (font (size 1.27 1.27) (thickness 0.15)) (justify left bottom) hide)
      )
      (property "Datasheet" "http://www.ti.com/lit/ds/symlink/tps2378.pdf" (at 35.56 -7.62 0)
        (effects (font (size 1.27 1.27) (thickness 0.15)) (justify left bottom) hide)
      )
      (property "MPN" "TPS2378DDA" (at 35.56 -12.7 0)
        (effects (font (size 1.27 1.27) (thickness 0.15)) (justify left bottom))
      )
      (property "Manufacturer" "Texas Instruments" (at 35.56 -10.16 0)
        (effects (font (size 1.27 1.27) (thickness 0.15)) (justify left bottom) hide)
      )
      (property "Author" "Antmicro" (at 35.56 -15.24 0)
        (effects (font (size 1.27 1.27) (thickness 0.15)) (justify left bottom) hide)
      )
      (property "License" "Apache-2.0" (at 35.56 -17.78 0)
        (effects (font (size 1.27 1.27) (thickness 0.15)) (justify left bottom) hide)
      )
      (property "ki_description" "Power Over Ethernet (POE) Controller, 57 V/ 500 µA, 40 V UVLO Threshold, SOIC-8" (at 0 0 0)
        (effects (font (size 1.27 1.27)) hide)
      )
      (symbol "TPS2378DDA_1_1"
        (polyline
          (pts
            (xy 2.54 2.54)
            (xy 17.78 2.54)
            (xy 17.78 -16.51)
            (xy 2.54 -16.51)
            (xy 2.54 2.54)
          )
          (stroke (width 0.254) (type default))
          (fill (type background))
        )
        (pin power_in line (at 0 0 0) (length 2.54)
          (name "VDD" (effects (font (size 1.27 1.27))))
          (number "1" (effects (font (size 1.27 1.27))))
        )
        (pin passive line (at 0 -2.54 0) (length 2.54)
          (name "DEN" (effects (font (size 1.27 1.27))))
          (number "2" (effects (font (size 1.27 1.27))))
        )
        (pin passive line (at 0 -8.89 0) (length 2.54)
          (name "CLS" (effects (font (size 1.27 1.27))))
          (number "3" (effects (font (size 1.27 1.27))))
        )
        (pin power_in line (at 0 -11.43 0) (length 2.54)
          (name "VSS" (effects (font (size 1.27 1.27))))
          (number "4" (effects (font (size 1.27 1.27))))
        )
        (pin passive line (at 20.32 -13.97 180) (length 2.54)
          (name "RTN" (effects (font (size 1.27 1.27))))
          (number "5" (effects (font (size 1.27 1.27))))
        )
        (pin passive line (at 20.32 -5.08 180) (length 2.54)
          (name "CDB" (effects (font (size 1.27 1.27))))
          (number "6" (effects (font (size 1.27 1.27))))
        )
        (pin passive line (at 20.32 -2.54 180) (length 2.54)
          (name "T2P" (effects (font (size 1.27 1.27))))
          (number "7" (effects (font (size 1.27 1.27))))
        )
        (pin passive line (at 20.32 0 180) (length 2.54)
          (name "APD" (effects (font (size 1.27 1.27))))
          (number "8" (effects (font (size 1.27 1.27))))
        )
        (pin power_in line (at 0 -13.97 0) (length 2.54)
          (name "EP" (effects (font (size 1.27 1.27))))
          (number "9" (effects (font (size 1.27 1.27))))
        )
      )
    )
	(symbol "scalenode-cm4-baseboard:TP_0.75mm_SMD" (pin_numbers hide) (pin_names hide) (in_bom yes) (on_board yes)
      (property "Reference" "TP" (at 17.78 -5.08 0)
        (effects (font (size 1.27 1.27) (thickness 0.15)) (justify left bottom))
      )
      (property "Value" "TP_0.75mm_SMD" (at 17.78 -7.62 0)
        (effects (font (size 1.27 1.27) (thickness 0.15)) (justify left bottom) hide)
      )
      (property "Footprint" "scalenode-cm4-baseboard-footprints:TP_SMD_0.75mm" (at 17.78 -10.16 0)
        (effects (font (size 1.27 1.27) (thickness 0.15)) (justify left bottom) hide)
      )
      (property "Datasheet" "" (at 17.78 -12.7 0)
        (effects (font (size 1.27 1.27) (thickness 0.15)) (justify left bottom) hide)
      )
      (property "MPN" "" (at 17.78 -15.24 0)
        (effects (font (size 1.27 1.27) (thickness 0.15)) (justify left bottom) hide)
      )
      (property "Manufacturer" "" (at 17.78 -17.78 0)
        (effects (font (size 1.27 1.27) (thickness 0.15)) (justify left bottom) hide)
      )
      (property "Author" "Antmicro" (at 17.78 -20.32 0)
        (effects (font (size 1.27 1.27) (thickness 0.15)) (justify left bottom) hide)
      )
      (property "License" "Apache-2.0" (at 17.78 -22.86 0)
        (effects (font (size 1.27 1.27) (thickness 0.15)) (justify left bottom) hide)
      )
      (property "ki_description" "SMT test point" (at 0 0 0)
        (effects (font (size 1.27 1.27)) hide)
      )
      (symbol "TP_0.75mm_SMD_1_1"
        (circle (center 3.175 0) (radius 0.635)
          (stroke (width 0.254) (type default))
          (fill (type none))
        )
        (pin passive line (at 0 0 0) (length 2.54)
          (name "1" (effects (font (size 1.27 1.27))))
          (number "1" (effects (font (size 1.27 1.27))))
        )
      )
    )
	(symbol "scalenode-cm4-baseboard:TP_1mm_SMD" (pin_numbers hide) (pin_names hide) (in_bom yes) (on_board yes)
      (property "Reference" "TP" (at 15.24 -5.08 0)
        (effects (font (size 1.27 1.27) (thickness 0.15)) (justify left bottom))
      )
      (property "Value" "TP_1mm_SMD" (at 15.24 -7.62 0)
        (effects (font (size 1.27 1.27) (thickness 0.15)) (justify left bottom) hide)
      )
      (property "Footprint" "scalenode-cm4-baseboard-footprints:TP_SMD_1mm" (at 15.24 -10.16 0)
        (effects (font (size 1.27 1.27) (thickness 0.15)) (justify left bottom) hide)
      )
      (property "Datasheet" "" (at 15.24 -12.7 0)
        (effects (font (size 1.27 1.27) (thickness 0.15)) (justify left bottom) hide)
      )
      (property "MPN" "" (at 0 0 0)
        (effects (font (size 1.27 1.27)) hide)
      )
      (property "Manufacturer" "" (at 0 0 0)
        (effects (font (size 1.27 1.27)) hide)
      )
      (property "Author" "Antmicro" (at 15.24 -15.24 0)
        (effects (font (size 1.27 1.27) (thickness 0.15)) (justify left bottom) hide)
      )
      (property "License" "Apache-2.0" (at 15.24 -17.78 0)
        (effects (font (size 1.27 1.27) (thickness 0.15)) (justify left bottom) hide)
      )
      (property "ki_description" "Test point 1mm SMD" (at 0 0 0)
        (effects (font (size 1.27 1.27)) hide)
      )
      (symbol "TP_1mm_SMD_1_1"
        (circle (center 3.175 0) (radius 0.635)
          (stroke (width 0.254) (type default))
          (fill (type none))
        )
        (pin passive line (at 0 0 0) (length 2.54)
          (name "1" (effects (font (size 1.27 1.27))))
          (number "1" (effects (font (size 1.27 1.27))))
        )
      )
    )
	(symbol "scalenode-cm4-baseboard:TS3USB30EDGSR" (in_bom yes) (on_board yes)
      (property "Reference" "U" (at 43.18 -2.54 0)
        (effects (font (size 1.27 1.27) (thickness 0.15)) (justify left bottom))
      )
      (property "Value" "TS3USB30EDGSR" (at 43.18 -7.62 0)
        (effects (font (size 1.27 1.27) (thickness 0.15)) (justify left bottom) hide)
      )
      (property "Footprint" "scalenode-cm4-baseboard-footprints:MSOP-10_W3mm" (at 43.18 -10.16 0)
        (effects (font (size 1.27 1.27) (thickness 0.15)) (justify left bottom) hide)
      )
      (property "Datasheet" "http://www.ti.com/general/docs/suppproductinfo.tsp?distId=10&gotoUrl=http%3A%2F%2Fwww.ti.com%2Flit%2Fgpn%2Fts3usb30e" (at 43.18 -12.7 0)
        (effects (font (size 1.27 1.27) (thickness 0.15)) (justify left bottom) hide)
      )
      (property "MPN" "TS3USB30EDGSR" (at 43.18 -5.08 0)
        (effects (font (size 1.27 1.27) (thickness 0.15)) (justify left bottom))
      )
      (property "Manufacturer" "Texas Instruments" (at 43.18 -15.24 0)
        (effects (font (size 1.27 1.27) (thickness 0.15)) (justify left bottom) hide)
      )
      (property "Author" "Antmicro" (at 43.18 -17.78 0)
        (effects (font (size 1.27 1.27) (thickness 0.15)) (justify left bottom) hide)
      )
      (property "License" "Apache-2.0" (at 43.18 -20.32 0)
        (effects (font (size 1.27 1.27) (thickness 0.15)) (justify left bottom) hide)
      )
      (symbol "TS3USB30EDGSR_1_1"
        (polyline
          (pts
            (xy 7.62 -13.97)
            (xy 8.89 -13.97)
          )
          (stroke (width 0.254) (type default))
          (fill (type background))
        )
        (polyline
          (pts
            (xy 7.62 -5.08)
            (xy 8.89 -5.08)
          )
          (stroke (width 0.254) (type default))
          (fill (type background))
        )
        (polyline
          (pts
            (xy 8.89 -8.89)
            (xy 7.62 -8.89)
          )
          (stroke (width 0.254) (type default))
          (fill (type background))
        )
        (polyline
          (pts
            (xy 8.89 0)
            (xy 7.62 0)
          )
          (stroke (width 0.254) (type default))
          (fill (type background))
        )
        (polyline
          (pts
            (xy 9.525 -9.525)
            (xy 13.97 -11.43)
          )
          (stroke (width 0.254) (type default))
          (fill (type background))
        )
        (polyline
          (pts
            (xy 9.525 -0.635)
            (xy 13.97 -2.54)
          )
          (stroke (width 0.254) (type default))
          (fill (type background))
        )
        (polyline
          (pts
            (xy 14.478 -11.43)
            (xy 15.24 -11.43)
          )
          (stroke (width 0.254) (type default))
          (fill (type background))
        )
        (polyline
          (pts
            (xy 14.478 -2.54)
            (xy 15.24 -2.54)
          )
          (stroke (width 0.254) (type default))
          (fill (type background))
        )
        (polyline
          (pts
            (xy 8.89 -13.97)
            (xy 10.795 -13.97)
            (xy 10.16 -13.335)
            (xy 9.525 -13.97)
          )
          (stroke (width 0.254) (type default))
          (fill (type background))
        )
        (polyline
          (pts
            (xy 8.89 -8.89)
            (xy 10.795 -8.89)
            (xy 10.16 -9.525)
            (xy 9.525 -8.89)
          )
          (stroke (width 0.254) (type default))
          (fill (type background))
        )
        (polyline
          (pts
            (xy 8.89 -5.08)
            (xy 10.795 -5.08)
            (xy 10.16 -4.445)
            (xy 9.525 -5.08)
          )
          (stroke (width 0.254) (type default))
          (fill (type background))
        )
        (polyline
          (pts
            (xy 8.89 0)
            (xy 10.795 0)
            (xy 10.16 -0.635)
            (xy 9.525 0)
          )
          (stroke (width 0.254) (type default))
          (fill (type background))
        )
        (rectangle (start 2.54 3.81) (end 19.05 -22.86)
          (stroke (width 0.254) (type default))
          (fill (type background))
        )
        (circle (center 14.224 -11.43) (radius 0.254)
          (stroke (width 0.254) (type default))
          (fill (type background))
        )
        (circle (center 14.224 -2.54) (radius 0.254)
          (stroke (width 0.254) (type default))
          (fill (type background))
        )
        (pin input line (at 0 -17.78 0) (length 2.54)
          (name "S" (effects (font (size 1.27 1.27))))
          (number "1" (effects (font (size 1.27 1.27))))
        )
        (pin power_in line (at 21.59 1.27 180) (length 2.54)
          (name "VCC" (effects (font (size 1.27 1.27))))
          (number "10" (effects (font (size 1.27 1.27))))
        )
        (pin bidirectional line (at 0 0 0) (length 2.54)
          (name "D1+" (effects (font (size 1.27 1.27))))
          (number "2" (effects (font (size 1.27 1.27))))
        )
        (pin bidirectional line (at 0 -5.08 0) (length 2.54)
          (name "D2+" (effects (font (size 1.27 1.27))))
          (number "3" (effects (font (size 1.27 1.27))))
        )
        (pin bidirectional line (at 21.59 -2.54 180) (length 2.54)
          (name "D+" (effects (font (size 1.27 1.27))))
          (number "4" (effects (font (size 1.27 1.27))))
        )
        (pin power_in line (at 21.59 -20.32 180) (length 2.54)
          (name "GND" (effects (font (size 1.27 1.27))))
          (number "5" (effects (font (size 1.27 1.27))))
        )
        (pin bidirectional line (at 21.59 -11.43 180) (length 2.54)
          (name "D-" (effects (font (size 1.27 1.27))))
          (number "6" (effects (font (size 1.27 1.27))))
        )
        (pin bidirectional line (at 0 -13.97 0) (length 2.54)
          (name "D2-" (effects (font (size 1.27 1.27))))
          (number "7" (effects (font (size 1.27 1.27))))
        )
        (pin bidirectional line (at 0 -8.89 0) (length 2.54)
          (name "D1-" (effects (font (size 1.27 1.27))))
          (number "8" (effects (font (size 1.27 1.27))))
        )
        (pin input line (at 0 -20.32 0) (length 2.54)
          (name "~{OE}" (effects (font (size 1.27 1.27))))
          (number "9" (effects (font (size 1.27 1.27))))
        )
      )
    )
	(symbol "scalenode-cm4-baseboard:URB4805YMD-30WR3" (in_bom yes) (on_board yes)
      (property "Reference" "U" (at 35.56 -2.54 0)
        (effects (font (size 1.27 1.27) (thickness 0.15)) (justify left bottom))
      )
      (property "Value" "URB4805YMD-30WR3" (at 35.56 -7.62 0)
        (effects (font (size 1.27 1.27) (thickness 0.15)) (justify left bottom) hide)
      )
      (property "Footprint" "scalenode-cm4-baseboard-footprints:URB4805YMD-30WR3" (at 35.56 -10.16 0)
        (effects (font (size 1.27 1.27) (thickness 0.15)) (justify left bottom) hide)
      )
      (property "Datasheet" "https://www.mornsun-power.com/html/pdf/URB4805YMD-30WR3.html" (at 35.56 -12.7 0)
        (effects (font (size 1.27 1.27) (thickness 0.15)) (justify left bottom) hide)
      )
      (property "Manufacturer" "Mornsun" (at 35.56 -15.24 0)
        (effects (font (size 1.27 1.27) (thickness 0.15)) (justify left bottom) hide)
      )
      (property "MPN" "URB4805YMD-30WR3" (at 35.56 -5.08 0)
        (effects (font (size 1.27 1.27) (thickness 0.15)) (justify left bottom))
      )
      (property "License" "Apache-2.0" (at 35.56 -20.32 0)
        (effects (font (size 1.27 1.27) (thickness 0.15)) (justify left bottom) hide)
      )
      (property "Author" "Antmicro" (at 35.56 -17.78 0)
        (effects (font (size 1.27 1.27) (thickness 0.15)) (justify left bottom) hide)
      )
      (property "ki_keywords" "SMT, PMIC, IC, DC-DC, CONVERTER, MODULE" (at 0 0 0)
        (effects (font (size 1.27 1.27)) hide)
      )
      (property "ki_description" "DC/DC converter" (at 0 0 0)
        (effects (font (size 1.27 1.27)) hide)
      )
      (symbol "URB4805YMD-30WR3_1_1"
        (rectangle (start 2.54 2.54) (end 17.78 -17.78)
          (stroke (width 0.254) (type default))
          (fill (type background))
        )
        (pin input line (at 0 -7.62 0) (length 2.54)
          (name "CTRL" (effects (font (size 1.27 1.27))))
          (number "1" (effects (font (size 1.27 1.27))))
        )
        (pin power_in line (at 0 -15.24 0) (length 2.54)
          (name "GND" (effects (font (size 1.27 1.27))))
          (number "2" (effects (font (size 1.27 1.27))))
        )
        (pin power_in line (at 0 0 0) (length 2.54)
          (name "V_{IN}" (effects (font (size 1.27 1.27))))
          (number "3" (effects (font (size 1.27 1.27))))
        )
        (pin power_out line (at 20.32 0 180) (length 2.54)
          (name "V_{O}" (effects (font (size 1.27 1.27))))
          (number "4" (effects (font (size 1.27 1.27))))
        )
        (pin passive line (at 20.32 -7.62 180) (length 2.54)
          (name "TRIM" (effects (font (size 1.27 1.27))))
          (number "5" (effects (font (size 1.27 1.27))))
        )
        (pin power_out line (at 20.32 -15.24 180) (length 2.54)
          (name "0V" (effects (font (size 1.27 1.27))))
          (number "6" (effects (font (size 1.27 1.27))))
        )
      )
    )
	(symbol "scalenode-cm4-baseboard:USB-Micro-B_Molex_473460001" (in_bom yes) (on_board yes)
      (property "Reference" "J" (at 24.765 2.54 0)
        (effects (font (size 1.27 1.27) (thickness 0.15)) (justify left bottom))
      )
      (property "Value" "USB-Micro-B_Molex_473460001" (at 24.765 0 0)
        (effects (font (size 1.27 1.27) (thickness 0.15)) (justify left bottom))
      )
      (property "Footprint" "scalenode-cm4-baseboard-footprints:USB-Micro-B_Receptacle_Molex_473460001" (at 24.765 -2.54 0)
        (effects (font (size 1.27 1.27) (thickness 0.15)) (justify left bottom) hide)
      )
      (property "Datasheet" "https://www.molex.com/pdm_docs/sd/473460001_sd.pdf" (at 24.765 -5.08 0)
        (effects (font (size 1.27 1.27) (thickness 0.15)) (justify left bottom) hide)
      )
      (property "MPN" "473460001" (at 24.765 -7.62 0)
        (effects (font (size 1.27 1.27) (thickness 0.15)) (justify left bottom) hide)
      )
      (property "Manufacturer" "Molex" (at 24.765 -10.16 0)
        (effects (font (size 1.27 1.27) (thickness 0.15)) (justify left bottom) hide)
      )
      (property "Author" "Antmicro" (at 24.765 -12.7 0)
        (effects (font (size 1.27 1.27) (thickness 0.15)) (justify left bottom) hide)
      )
      (property "License" "Apache-2.0" (at 24.765 -15.24 0)
        (effects (font (size 1.27 1.27) (thickness 0.15)) (justify left bottom) hide)
      )
      (property "ki_keywords" "USB, MICRO, CONNECTOR, SMT, HORIZONTAL" (at 0 0 0)
        (effects (font (size 1.27 1.27)) hide)
      )
      (property "ki_description" "USB - micro B USB 2.0 Receptacle Connector 5 Position Surface Mount, Right Angle" (at 0 0 0)
        (effects (font (size 1.27 1.27)) hide)
      )
      (symbol "USB-Micro-B_Molex_473460001_0_1"
        (rectangle (start -13.335 -7.366) (end -13.97 -12.446)
          (stroke (width 0.127) (type default))
          (fill (type outline))
        )
        (polyline
          (pts
            (xy -13.97 -13.97)
            (xy -15.24 -12.7)
          )
          (stroke (width 0.254) (type default))
          (fill (type none))
        )
        (polyline
          (pts
            (xy -12.7 -13.97)
            (xy -13.97 -13.97)
          )
          (stroke (width 0.254) (type default))
          (fill (type none))
        )
        (polyline
          (pts
            (xy -12.7 -13.97)
            (xy -12.7 -5.715)
          )
          (stroke (width 0.254) (type default))
          (fill (type none))
        )
        (polyline
          (pts
            (xy -12.7 -5.715)
            (xy -13.97 -5.715)
          )
          (stroke (width 0.254) (type default))
          (fill (type none))
        )
        (polyline
          (pts
            (xy -13.97 -5.715)
            (xy -15.24 -6.985)
            (xy -15.24 -12.7)
          )
          (stroke (width 0.254) (type default))
          (fill (type none))
        )
      )
      (symbol "USB-Micro-B_Molex_473460001_1_1"
        (rectangle (start -21.59 2.54) (end -2.54 -22.86)
          (stroke (width 0.254) (type default))
          (fill (type background))
        )
        (circle (center -18.796 -10.414) (radius 0.284)
          (stroke (width 0.254) (type default))
          (fill (type outline))
        )
        (circle (center -17.907 -13.208) (radius 0.5236)
          (stroke (width 0.254) (type default))
          (fill (type outline))
        )
        (rectangle (start -17.399 -10.414) (end -16.637 -9.652)
          (stroke (width 0.254) (type default))
          (fill (type outline))
        )
        (polyline
          (pts
            (xy -17.907 -13.081)
            (xy -17.907 -8.763)
          )
          (stroke (width 0.254) (type default))
          (fill (type background))
        )
        (polyline
          (pts
            (xy -17.907 -12.319)
            (xy -18.796 -11.43)
            (xy -18.796 -10.795)
          )
          (stroke (width 0.254) (type default))
          (fill (type background))
        )
        (polyline
          (pts
            (xy -17.907 -11.938)
            (xy -17.018 -11.049)
            (xy -17.018 -10.414)
          )
          (stroke (width 0.254) (type default))
          (fill (type background))
        )
        (polyline
          (pts
            (xy -18.542 -8.763)
            (xy -17.907 -7.62)
            (xy -17.272 -8.763)
            (xy -18.542 -8.763)
          )
          (stroke (width 0.254) (type default))
          (fill (type outline))
        )
        (pin passive line (at 0 0 180) (length 2.54)
          (name "VBUS" (effects (font (size 1.27 1.27))))
          (number "1" (effects (font (size 1.27 1.27))))
        )
        (pin bidirectional line (at 0 -7.62 180) (length 2.54)
          (name "D-" (effects (font (size 1.27 1.27))))
          (number "2" (effects (font (size 1.27 1.27))))
        )
        (pin bidirectional line (at 0 -5.08 180) (length 2.54)
          (name "D+" (effects (font (size 1.27 1.27))))
          (number "3" (effects (font (size 1.27 1.27))))
        )
        (pin bidirectional line (at 0 -12.7 180) (length 2.54)
          (name "ID" (effects (font (size 1.27 1.27))))
          (number "4" (effects (font (size 1.27 1.27))))
        )
        (pin power_in line (at 0 -17.78 180) (length 2.54)
          (name "GND" (effects (font (size 1.27 1.27))))
          (number "5" (effects (font (size 1.27 1.27))))
        )
        (pin passive line (at 0 -20.32 180) (length 2.54)
          (name "SHIELD" (effects (font (size 1.27 1.27))))
          (number "SH" (effects (font (size 1.27 1.27))))
        )
      )
    )
	(symbol "scalenode-cm4-baseboard:antmicro_logo" (in_bom yes) (on_board yes)
      (property "Reference" "N" (at 15.24 -5.08 0)
        (effects (font (size 1.27 1.27) (thickness 0.15)) (justify left bottom))
      )
      (property "Value" "antmicro_logo" (at 15.24 -7.62 0)
        (effects (font (size 1.27 1.27) (thickness 0.15)) (justify left bottom))
      )
      (property "Footprint" "scalenode-cm4-baseboard-footprints:antmicro-logo" (at 15.24 -10.16 0)
        (effects (font (size 1.27 1.27) (thickness 0.15)) (justify left bottom) hide)
      )
      (property "Datasheet" "" (at 15.24 -12.7 0)
        (effects (font (size 1.27 1.27) (thickness 0.15)) (justify left bottom) hide)
      )
      (property "MPN" "" (at 0 0 0)
        (effects (font (size 1.27 1.27)) hide)
      )
      (property "Manufacturer" "" (at 15.24 -20.32 0)
        (effects (font (size 1.27 1.27) (thickness 0.15)) (justify left bottom) hide)
      )
      (property "Author" "Antmicro" (at 15.24 -15.24 0)
        (effects (font (size 1.27 1.27) (thickness 0.15)) (justify left bottom) hide)
      )
      (property "License" "Apache-2.0" (at 15.24 -17.78 0)
        (effects (font (size 1.27 1.27) (thickness 0.15)) (justify left bottom) hide)
      )
      (symbol "antmicro_logo_1_1"
        (text "Logo" (at 0 0 0)
          (effects (font (size 1.27 1.27) (thickness 0.15)) (justify left bottom))
        )
      )
    )
	(symbol "scalenode-cm4-baseboard:oshw_logo" (in_bom yes) (on_board yes)
      (property "Reference" "N" (at 15.24 -5.08 0)
        (effects (font (size 1.27 1.27) (thickness 0.15)) (justify left bottom))
      )
      (property "Value" "oshw_logo" (at 15.24 -7.62 0)
        (effects (font (size 1.27 1.27) (thickness 0.15)) (justify left bottom))
      )
      (property "Footprint" "scalenode-cm4-baseboard-footprints:oshw-logo" (at 15.24 -10.16 0)
        (effects (font (size 1.27 1.27) (thickness 0.15)) (justify left bottom) hide)
      )
      (property "Datasheet" "" (at 15.24 -12.7 0)
        (effects (font (size 1.27 1.27) (thickness 0.15)) (justify left bottom) hide)
      )
      (property "Author" "Antmicro" (at 15.24 -15.24 0)
        (effects (font (size 1.27 1.27) (thickness 0.15)) (justify left bottom) hide)
      )
      (property "License" "Apache-2.0" (at 15.24 -17.78 0)
        (effects (font (size 1.27 1.27) (thickness 0.15)) (justify left bottom) hide)
      )
      (property "MPN" "" (at 0 0 0)
        (effects (font (size 1.27 1.27)) hide)
      )
      (property "Manufacturer" "" (at 15.24 -20.32 0)
        (effects (font (size 1.27 1.27) (thickness 0.15)) (justify left bottom) hide)
      )
      (symbol "oshw_logo_1_1"
        (text "Logo" (at 0 0 0)
          (effects (font (size 1.27 1.27) (thickness 0.15)) (justify left bottom))
        )
      )
    )
)
